FILE_TYPE = MACRO_DRAWING;
SET COLOR_WIRE YELLOW;
SET COLOR_PROP MONO;
SET COLOR_DOT WHITE;
SET COLOR_ARC YELLOW;
SET COLOR_BODY GREEN;
SET COLOR_NOTE MONO;
SET PROP_DISPLAY VALUE;
SET PAGE_NUMBER P147;
FORCEADD OFFPAGE..2
(2300 4250);
FORCEPROP 2 LAST $XR0 151 
J 0
(2669 4250);
DISPLAY 0.638298 (2669 4250);
PAINT MONO (2669 4250);
FORCEPROP 2 LAST CDS_LIB mstr_standard
J 0
(2300 4250);
PAINT MONO (2300 4250);
DISPLAY INVISIBLE (2300 4250);
FORCEPROP 2 LAST PATH I10
J 0
(2675 4300);
DISPLAY 1.021277 (2675 4300);
PAINT ORANGE (2675 4300);
DISPLAY INVISIBLE (2675 4300);
FORCEPROP 1 LAST OFFPAGE TRUE
J 0
(2625 4125);
DISPLAY 0.872340 (2625 4125);
PAINT GREEN (2625 4125);
DISPLAY INVISIBLE (2625 4125);
FORCEPROP 1 LAST COMMENT_BODY TRUE
J 0
(2255 4155);
DISPLAY 0.872340 (2255 4155);
PAINT GREEN (2255 4155);
DISPLAY INVISIBLE (2255 4155);
FORCEADD OFFPAGE..1
(-4775 3500);
FORCEPROP 2 LAST $XR0 21 
J 0
(-4996 3500);
DISPLAY 0.638298 (-4996 3500);
PAINT MONO (-4996 3500);
FORCEPROP 2 LAST $XR1 190 
J 0
(-5116 3500);
DISPLAY 0.638298 (-5116 3500);
PAINT MONO (-5116 3500);
FORCEPROP 2 LAST PATH I100
J 0
(-4725 3575);
DISPLAY 1.021277 (-4725 3575);
PAINT ORANGE (-4725 3575);
DISPLAY INVISIBLE (-4725 3575);
FORCEPROP 2 LAST CDS_LIB mstr_standard
J 0
(-4775 3500);
PAINT MONO (-4775 3500);
DISPLAY INVISIBLE (-4775 3500);
FORCEPROP 2 LAST BOM_COST SM_CONTROLLER
J 0
(-4325 3550);
PAINT MONO (-4325 3550);
DISPLAY INVISIBLE (-4325 3550);
FORCEPROP 2 LAST ROOM BMC
J 0
(-5025 3575);
DISPLAY 1.361702 (-5025 3575);
PAINT ORANGE (-5025 3575);
DISPLAY INVISIBLE (-5025 3575);
FORCEPROP 1 LAST OFFPAGE TRUE
J 0
(-4450 3375);
DISPLAY 0.872340 (-4450 3375);
PAINT GREEN (-4450 3375);
DISPLAY INVISIBLE (-4450 3375);
FORCEPROP 1 LAST COMMENT_BODY TRUE
J 0
(-4650 3400);
DISPLAY 0.872340 (-4650 3400);
PAINT GREEN (-4650 3400);
DISPLAY INVISIBLE (-4650 3400);
FORCEADD OFFPAGE..2
(1075 2650);
FORCEPROP 2 LAST $XR2 190 
J 0
(1504 2650);
DISPLAY 0.638298 (1504 2650);
PAINT MONO (1504 2650);
FORCEPROP 2 LAST $XR1 157 
J 0
(1384 2650);
DISPLAY 0.638298 (1384 2650);
PAINT MONO (1384 2650);
FORCEPROP 2 LAST $XR0 119 
J 0
(1264 2650);
DISPLAY 0.638298 (1264 2650);
PAINT MONO (1264 2650);
FORCEPROP 2 LAST PATH I102
J 0
(1250 2725);
DISPLAY 1.021277 (1250 2725);
PAINT ORANGE (1250 2725);
DISPLAY INVISIBLE (1250 2725);
FORCEPROP 2 LAST CDS_LIB mstr_standard
J 0
(1075 2650);
PAINT MONO (1075 2650);
DISPLAY INVISIBLE (1075 2650);
FORCEPROP 1 LAST OFFPAGE TRUE
J 0
(1400 2525);
DISPLAY 0.872340 (1400 2525);
PAINT GREEN (1400 2525);
DISPLAY INVISIBLE (1400 2525);
FORCEPROP 1 LAST COMMENT_BODY TRUE
J 0
(1030 2555);
DISPLAY 0.872340 (1030 2555);
PAINT GREEN (1030 2555);
DISPLAY INVISIBLE (1030 2555);
FORCEADD OFFPAGE..5
(-4675 2750);
FORCEPROP 2 LAST $XR0 249 
J 0
(-4930 2750);
DISPLAY 0.638298 (-4930 2750);
PAINT MONO (-4930 2750);
FORCEPROP 1 LAST COMMENT_BODY TRUE
J 0
(-4575 2675);
DISPLAY 0.872340 (-4575 2675);
PAINT GREEN (-4575 2675);
DISPLAY INVISIBLE (-4575 2675);
FORCEPROP 1 LAST OFFPAGE TRUE
J 0
(-4350 2625);
DISPLAY 0.872340 (-4350 2625);
PAINT GREEN (-4350 2625);
DISPLAY INVISIBLE (-4350 2625);
FORCEPROP 2 LAST CDS_LIB mstr_standard
J 0
(-4675 2750);
PAINT MONO (-4675 2750);
DISPLAY INVISIBLE (-4675 2750);
FORCEPROP 2 LAST PATH I103
J 0
(-4625 2825);
DISPLAY 1.021277 (-4625 2825);
PAINT ORANGE (-4625 2825);
DISPLAY INVISIBLE (-4625 2825);
FORCEADD OFFPAGE..5
(-4675 2800);
FORCEPROP 2 LAST $XR0 200 
J 0
(-5020 2800);
DISPLAY 0.638298 (-5020 2800);
PAINT MONO (-5020 2800);
FORCEPROP 1 LAST COMMENT_BODY TRUE
J 0
(-4575 2725);
DISPLAY 0.872340 (-4575 2725);
PAINT GREEN (-4575 2725);
DISPLAY INVISIBLE (-4575 2725);
FORCEPROP 1 LAST OFFPAGE TRUE
J 0
(-4350 2675);
DISPLAY 0.872340 (-4350 2675);
PAINT GREEN (-4350 2675);
DISPLAY INVISIBLE (-4350 2675);
FORCEPROP 2 LAST PATH I104
J 0
(-4625 2875);
DISPLAY 1.021277 (-4625 2875);
PAINT ORANGE (-4625 2875);
DISPLAY INVISIBLE (-4625 2875);
FORCEPROP 2 LAST CDS_LIB mstr_standard
J 0
(-4675 2800);
PAINT MONO (-4675 2800);
DISPLAY INVISIBLE (-4675 2800);
FORCEADD OFFPAGE..1
(-4650 3100);
FORCEPROP 2 LAST $XR0 133 
J 0
(-4902 3100);
DISPLAY 0.638298 (-4902 3100);
PAINT MONO (-4902 3100);
FORCEPROP 2 LAST $XR1 249 
J 0
(-5022 3100);
DISPLAY 0.638298 (-5022 3100);
PAINT MONO (-5022 3100);
FORCEPROP 2 LAST $XR2 119 
J 0
(-5022 3064);
DISPLAY 0.638298 (-5022 3064);
PAINT MONO (-5022 3064);
FORCEPROP 1 LAST COMMENT_BODY TRUE
J 0
(-4525 3000);
DISPLAY 0.872340 (-4525 3000);
PAINT GREEN (-4525 3000);
DISPLAY INVISIBLE (-4525 3000);
FORCEPROP 1 LAST OFFPAGE TRUE
J 0
(-4325 2975);
DISPLAY 0.872340 (-4325 2975);
PAINT GREEN (-4325 2975);
DISPLAY INVISIBLE (-4325 2975);
FORCEPROP 2 LAST CDS_LIB mstr_standard
J 0
(-4650 3100);
PAINT MONO (-4650 3100);
DISPLAY INVISIBLE (-4650 3100);
FORCEPROP 2 LAST PATH I105
J 0
(-4600 3175);
DISPLAY 1.021277 (-4600 3175);
PAINT ORANGE (-4600 3175);
DISPLAY INVISIBLE (-4600 3175);
FORCEADD AST2520A1-GP-GP..6
(-1825 3400);
FORCEPROP 1 LAST LOCATION U25W4
J 0
(-3225 4825);
DISPLAY 0.617021 (-3225 4825);
PAINT GREEN (-3225 4825);
FORCEPROP 1 LAST VALUE AST2520A1-GP-GP
J 0
(-3225 1950);
DISPLAY 0.617021 (-3225 1950);
PAINT GREEN (-3225 1950);
FORCEPROP 1 LAST CDS_LMAN_SYM_OUTLINE -1400,1400,1400,-1400
J 0
(-1825 3400);
DISPLAY 0.468085 (-1825 3400);
PAINT GREEN (-1825 3400);
DISPLAY INVISIBLE (-1825 3400);
FORCEPROP 1 LAST PACK_TYPE ASIC2-GB1
J 0
(-1825 3400);
DISPLAY 0.617021 (-1825 3400);
PAINT GREEN (-1825 3400);
DISPLAY INVISIBLE (-1825 3400);
FORCEPROP 1 LAST PATH I106
J 0
(-1825 3400);
DISPLAY 0.617021 (-1825 3400);
PAINT GREEN (-1825 3400);
DISPLAY INVISIBLE (-1825 3400);
FORCEPROP 1 LAST PART_NUMBER 071.2520A.M001
J 0
(-1825 3400);
DISPLAY 0.617021 (-1825 3400);
PAINT GREEN (-1825 3400);
DISPLAY INVISIBLE (-1825 3400);
FORCEPROP 2 LAST CDS_LIB w_hdl
J 0
(-1825 3400);
PAINT MONO (-1825 3400);
DISPLAY INVISIBLE (-1825 3400);
FORCEADD OFFPAGE..2
(2300 4150);
FORCEPROP 2 LAST $XR1 139 
J 0
(2609 4150);
DISPLAY 0.638298 (2609 4150);
PAINT MONO (2609 4150);
FORCEPROP 2 LAST $XR2 ?
J 0
(2609 4150);
DISPLAY 0.638298 (2609 4150);
PAINT MONO (2609 4150);
FORCEPROP 2 LAST $XR0 121 
J 0
(2489 4150);
DISPLAY 0.638298 (2489 4150);
PAINT MONO (2489 4150);
FORCEPROP 2 LAST CDS_LIB mstr_standard
J 0
(2300 4150);
PAINT ORANGE (2300 4150);
DISPLAY INVISIBLE (2300 4150);
FORCEPROP 2 LAST PATH I11
J 0
(2625 4200);
DISPLAY 1.021277 (2625 4200);
PAINT ORANGE (2625 4200);
DISPLAY INVISIBLE (2625 4200);
FORCEPROP 1 LAST OFFPAGE TRUE
J 0
(2625 4025);
DISPLAY 0.872340 (2625 4025);
PAINT GREEN (2625 4025);
DISPLAY INVISIBLE (2625 4025);
FORCEPROP 1 LAST COMMENT_BODY TRUE
J 0
(2255 4055);
DISPLAY 0.872340 (2255 4055);
PAINT GREEN (2255 4055);
DISPLAY INVISIBLE (2255 4055);
FORCEADD OFFPAGE..2
(2300 4200);
FORCEPROP 2 LAST $XR1 139 
J 0
(2609 4200);
DISPLAY 0.638298 (2609 4200);
PAINT MONO (2609 4200);
FORCEPROP 2 LAST $XR2 ?
J 0
(2609 4200);
DISPLAY 0.638298 (2609 4200);
PAINT MONO (2609 4200);
FORCEPROP 2 LAST $XR0 121 
J 0
(2489 4200);
DISPLAY 0.638298 (2489 4200);
PAINT MONO (2489 4200);
FORCEPROP 2 LAST CDS_LIB mstr_standard
J 0
(2300 4200);
PAINT MONO (2300 4200);
DISPLAY INVISIBLE (2300 4200);
FORCEPROP 2 LAST PATH I12
J 0
(2625 4250);
DISPLAY 1.021277 (2625 4250);
PAINT ORANGE (2625 4250);
DISPLAY INVISIBLE (2625 4250);
FORCEPROP 1 LAST OFFPAGE TRUE
J 0
(2625 4075);
DISPLAY 0.872340 (2625 4075);
PAINT GREEN (2625 4075);
DISPLAY INVISIBLE (2625 4075);
FORCEPROP 1 LAST COMMENT_BODY TRUE
J 0
(2255 4105);
DISPLAY 0.872340 (2255 4105);
PAINT GREEN (2255 4105);
DISPLAY INVISIBLE (2255 4105);
FORCEADD OFFPAGE..2
(1775 4000);
FORCEPROP 2 LAST $XR0 151 
J 0
(1964 4000);
DISPLAY 0.638298 (1964 4000);
PAINT MONO (1964 4000);
FORCEPROP 2 LAST $XR1 186 
J 0
(1964 4000);
DISPLAY 0.638298 (1964 4000);
PAINT MONO (1964 4000);
FORCEPROP 2 LAST CDS_LIB mstr_standard
J 0
(1775 4000);
PAINT ORANGE (1775 4000);
DISPLAY INVISIBLE (1775 4000);
FORCEPROP 2 LAST PATH I13
J 0
(1975 4050);
DISPLAY 1.021277 (1975 4050);
PAINT ORANGE (1975 4050);
DISPLAY INVISIBLE (1975 4050);
FORCEPROP 1 LAST OFFPAGE TRUE
J 0
(2100 3875);
DISPLAY 0.872340 (2100 3875);
PAINT GREEN (2100 3875);
DISPLAY INVISIBLE (2100 3875);
FORCEPROP 1 LAST COMMENT_BODY TRUE
J 0
(1730 3905);
DISPLAY 0.872340 (1730 3905);
PAINT GREEN (1730 3905);
DISPLAY INVISIBLE (1730 3905);
FORCEADD OFFPAGE..2
(1775 3900);
FORCEPROP 2 LAST $XR0 151 
J 0
(1964 3900);
DISPLAY 0.638298 (1964 3900);
PAINT MONO (1964 3900);
FORCEPROP 2 LAST CDS_LIB mstr_standard
J 0
(1775 3900);
PAINT MONO (1775 3900);
DISPLAY INVISIBLE (1775 3900);
FORCEPROP 2 LAST PATH I14
J 0
(1975 3950);
DISPLAY 1.021277 (1975 3950);
PAINT ORANGE (1975 3950);
DISPLAY INVISIBLE (1975 3950);
FORCEPROP 1 LAST OFFPAGE TRUE
J 0
(2100 3775);
DISPLAY 0.872340 (2100 3775);
PAINT GREEN (2100 3775);
DISPLAY INVISIBLE (2100 3775);
FORCEPROP 1 LAST COMMENT_BODY TRUE
J 0
(1730 3805);
DISPLAY 0.872340 (1730 3805);
PAINT GREEN (1730 3805);
DISPLAY INVISIBLE (1730 3805);
FORCEADD OFFPAGE..2
(1775 3850);
FORCEPROP 2 LAST $XR0 151 
J 0
(2384 3850);
DISPLAY 0.638298 (2384 3850);
PAINT MONO (2384 3850);
FORCEPROP 2 LAST CDS_LIB mstr_standard
J 0
(1775 3850);
PAINT MONO (1775 3850);
DISPLAY INVISIBLE (1775 3850);
FORCEPROP 2 LAST PATH I15
J 0
(2400 3900);
DISPLAY 1.021277 (2400 3900);
PAINT ORANGE (2400 3900);
DISPLAY INVISIBLE (2400 3900);
FORCEPROP 1 LAST OFFPAGE TRUE
J 0
(2100 3725);
DISPLAY 0.872340 (2100 3725);
PAINT GREEN (2100 3725);
DISPLAY INVISIBLE (2100 3725);
FORCEPROP 1 LAST COMMENT_BODY TRUE
J 0
(1730 3755);
DISPLAY 0.872340 (1730 3755);
PAINT GREEN (1730 3755);
DISPLAY INVISIBLE (1730 3755);
FORCEADD OFFPAGE..2
(1775 3750);
FORCEPROP 2 LAST $XR0 186 
J 0
(1964 3750);
DISPLAY 0.638298 (1964 3750);
PAINT MONO (1964 3750);
FORCEPROP 2 LAST CDS_LIB mstr_standard
J 0
(1775 3750);
PAINT ORANGE (1775 3750);
DISPLAY INVISIBLE (1775 3750);
FORCEPROP 2 LAST PATH I16
J 0
(1975 3800);
DISPLAY 1.021277 (1975 3800);
PAINT ORANGE (1975 3800);
DISPLAY INVISIBLE (1975 3800);
FORCEPROP 1 LAST OFFPAGE TRUE
J 0
(2100 3625);
DISPLAY 0.872340 (2100 3625);
PAINT GREEN (2100 3625);
DISPLAY INVISIBLE (2100 3625);
FORCEPROP 1 LAST COMMENT_BODY TRUE
J 0
(1730 3655);
DISPLAY 0.872340 (1730 3655);
PAINT GREEN (1730 3655);
DISPLAY INVISIBLE (1730 3655);
FORCEADD OFFPAGE..2
(1775 3800);
FORCEPROP 2 LAST $XR0 186 
J 0
(1964 3800);
DISPLAY 0.638298 (1964 3800);
PAINT MONO (1964 3800);
FORCEPROP 2 LAST CDS_LIB mstr_standard
J 0
(1775 3800);
PAINT ORANGE (1775 3800);
DISPLAY INVISIBLE (1775 3800);
FORCEPROP 2 LAST PATH I17
J 0
(1975 3850);
DISPLAY 1.021277 (1975 3850);
PAINT ORANGE (1975 3850);
DISPLAY INVISIBLE (1975 3850);
FORCEPROP 1 LAST OFFPAGE TRUE
J 0
(2100 3675);
DISPLAY 0.872340 (2100 3675);
PAINT GREEN (2100 3675);
DISPLAY INVISIBLE (2100 3675);
FORCEPROP 1 LAST COMMENT_BODY TRUE
J 0
(1730 3705);
DISPLAY 0.872340 (1730 3705);
PAINT GREEN (1730 3705);
DISPLAY INVISIBLE (1730 3705);
FORCEADD OFFPAGE..2
(1775 3700);
FORCEPROP 2 LAST $XR1 151 
J 0
(1964 3700);
DISPLAY 0.638298 (1964 3700);
PAINT MONO (1964 3700);
FORCEPROP 2 LAST $XR0 147 
J 0
(2064 3700);
DISPLAY 0.638298 (2064 3700);
PAINT MONO (2064 3700);
FORCEPROP 2 LAST CDS_LIB mstr_standard
J 0
(1775 3700);
PAINT ORANGE (1775 3700);
DISPLAY INVISIBLE (1775 3700);
FORCEPROP 2 LAST PATH I18
J 0
(2025 3750);
DISPLAY 1.021277 (2025 3750);
PAINT ORANGE (2025 3750);
DISPLAY INVISIBLE (2025 3750);
FORCEPROP 1 LAST OFFPAGE TRUE
J 0
(2100 3575);
DISPLAY 0.872340 (2100 3575);
PAINT GREEN (2100 3575);
DISPLAY INVISIBLE (2100 3575);
FORCEPROP 1 LAST COMMENT_BODY TRUE
J 0
(1730 3605);
DISPLAY 0.872340 (1730 3605);
PAINT GREEN (1730 3605);
DISPLAY INVISIBLE (1730 3605);
FORCEADD OFFPAGE..2
(1775 3650);
FORCEPROP 2 LAST $XR0 147 
J 0
(2064 3650);
DISPLAY 0.638298 (2064 3650);
PAINT MONO (2064 3650);
FORCEPROP 2 LAST $XR1 151 
J 0
(1964 3650);
DISPLAY 0.638298 (1964 3650);
PAINT MONO (1964 3650);
FORCEPROP 2 LAST CDS_LIB mstr_standard
J 0
(1775 3650);
PAINT ORANGE (1775 3650);
DISPLAY INVISIBLE (1775 3650);
FORCEPROP 2 LAST PATH I19
J 0
(2075 3700);
DISPLAY 1.021277 (2075 3700);
PAINT ORANGE (2075 3700);
DISPLAY INVISIBLE (2075 3700);
FORCEPROP 1 LAST OFFPAGE TRUE
J 0
(2100 3525);
DISPLAY 0.872340 (2100 3525);
PAINT GREEN (2100 3525);
DISPLAY INVISIBLE (2100 3525);
FORCEPROP 1 LAST COMMENT_BODY TRUE
J 0
(1730 3555);
DISPLAY 0.872340 (1730 3555);
PAINT GREEN (1730 3555);
DISPLAY INVISIBLE (1730 3555);
FORCEADD OFFPAGE..2
(2300 4400);
FORCEPROP 2 LAST $XR0 139 
J 0
(2489 4400);
DISPLAY 0.638298 (2489 4400);
PAINT MONO (2489 4400);
FORCEPROP 2 LAST $XR2 121 
J 0
(2609 4400);
DISPLAY 0.638298 (2609 4400);
PAINT MONO (2609 4400);
FORCEPROP 2 LAST $XR1 151 
J 0
(2609 4400);
DISPLAY 0.638298 (2609 4400);
PAINT MONO (2609 4400);
FORCEPROP 2 LAST CDS_LIB mstr_standard
J 0
(2300 4400);
PAINT ORANGE (2300 4400);
DISPLAY INVISIBLE (2300 4400);
FORCEPROP 2 LAST PATH I2
J 0
(2625 4450);
DISPLAY 1.021277 (2625 4450);
PAINT ORANGE (2625 4450);
DISPLAY INVISIBLE (2625 4450);
FORCEPROP 1 LAST OFFPAGE TRUE
J 0
(2625 4275);
DISPLAY 0.872340 (2625 4275);
PAINT GREEN (2625 4275);
DISPLAY INVISIBLE (2625 4275);
FORCEPROP 1 LAST COMMENT_BODY TRUE
J 0
(2255 4305);
DISPLAY 0.872340 (2255 4305);
PAINT GREEN (2255 4305);
DISPLAY INVISIBLE (2255 4305);
FORCEADD W_VCC_CIRCLE..1
(2350 2525);
FORCEPROP 3 LASTPIN (2350 2525) SIG_NAME VCC_ADCAV3V3\g
J 0
(2360 2535);
DISPLAY 0.659574 (2360 2535);
PAINT MONO (2360 2535);
DISPLAY INVISIBLE (2360 2535);
FORCEPROP 1 LAST HDL_POWER VCC_ADCAV3V3
J 1
(2371 2600);
DISPLAY 0.872340 (2371 2600);
PAINT ORANGE (2371 2600);
FORCEPROP 2 LAST CDS_LIB w_power
J 0
(2350 2525);
PAINT MONO (2350 2525);
DISPLAY INVISIBLE (2350 2525);
FORCEPROP 1 LAST CDS_LMAN_SYM_OUTLINE -100,100,100,-100
J 0
(2350 2525);
DISPLAY 0.468085 (2350 2525);
PAINT GREEN (2350 2525);
DISPLAY INVISIBLE (2350 2525);
FORCEPROP 1 LAST PATH I20
J 0
(2350 2525);
DISPLAY 0.617021 (2350 2525);
PAINT GREEN (2350 2525);
DISPLAY INVISIBLE (2350 2525);
FORCEPROP 1 LAST BODY_TYPE PLUMBING
J 0
(2362 2519);
DISPLAY 0.340426 (2362 2519);
PAINT GREEN (2362 2519);
DISPLAY INVISIBLE (2362 2519);
FORCEADD RES..1
(925 4200);
FORCEPROP 1 LAST VALUE 22.1
J 2
(1125 4200);
DISPLAY 0.617021 (1125 4200);
PAINT SKYBLUE (1125 4200);
FORCEPROP 1 LAST TOLERANCE 1.0%
J 2
(1225 4200);
DISPLAY 0.617021 (1225 4200);
PAINT SKYBLUE (1225 4200);
FORCEPROP 1 LASTPIN (1025 4200) $PN 2
J 0
(987 4212);
DISPLAY 0.617021 (987 4212);
PAINT ORANGE (987 4212);
FORCEPROP 1 LAST LOCATION R25W90
J 0
(700 4200);
DISPLAY 0.617021 (700 4200);
PAINT AQUA (700 4200);
FORCEPROP 1 LASTPIN (825 4200) $PN 1
J 0
(837 4212);
DISPLAY 0.617021 (837 4212);
PAINT ORANGE (837 4212);
FORCEPROP 1 LAST PATH I21
J 0
(875 4350);
DISPLAY 0.978723 (875 4350);
PAINT WHITE (875 4350);
DISPLAY INVISIBLE (875 4350);
FORCEPROP 2 LAST CDS_LIB mstr_discrete
J 0
(925 4200);
PAINT ORANGE (925 4200);
DISPLAY INVISIBLE (925 4200);
FORCEPROP 2 LAST SEC_TYPE 0402
J 0
(875 4400);
DISPLAY 1.021277 (875 4400);
PAINT ORANGE (875 4400);
DISPLAY INVISIBLE (875 4400);
FORCEPROP 2 LAST SEC 1
J 0
(875 4400);
DISPLAY 0.680851 (875 4400);
PAINT MONO (875 4400);
DISPLAY INVISIBLE (875 4400);
FORCEPROP 1 LAST PART_NUMBER G21796-250
J 0
(875 4300);
DISPLAY 0.978723 (875 4300);
PAINT BLUE (875 4300);
DISPLAY INVISIBLE (875 4300);
FORCEPROP 2 LAST BOM_COST SM_CONTROLLER
J 0
(875 4350);
DISPLAY 1.021277 (875 4350);
PAINT ORANGE (875 4350);
DISPLAY INVISIBLE (875 4350);
FORCEPROP 2 LAST ROOM BMC
J 0
(875 4300);
DISPLAY 1.021277 (875 4300);
PAINT ORANGE (875 4300);
DISPLAY INVISIBLE (875 4300);
FORCEPROP 1 LAST PACK_TYPE 0402
J 0
(1175 4050);
DISPLAY 0.978723 (1175 4050);
PAINT SKYBLUE (1175 4050);
DISPLAY INVISIBLE (1175 4050);
FORCEPROP 1 LAST WATTAGE 1/16W
J 2
(900 4050);
DISPLAY 0.978723 (900 4050);
PAINT SKYBLUE (900 4050);
DISPLAY INVISIBLE (900 4050);
FORCEPROP 0 LAST CDS_SEC 1
J 0
(875 4300);
PAINT MONO (875 4300);
DISPLAY INVISIBLE (875 4300);
FORCEPROP 1 LAST MATERIAL CHIP
J 2
(800 4200);
DISPLAY 0.617021 (800 4200);
PAINT SKYBLUE (800 4200);
DISPLAY INVISIBLE (800 4200);
FORCEPROP 2 LAST CDS_LOCATION R25W90
J 0
(875 4250);
DISPLAY 0.617021 (875 4250);
PAINT AQUA (875 4250);
DISPLAY INVISIBLE (875 4250);
FORCEADD RES..1
(925 4150);
FORCEPROP 1 LAST LOCATION R25W89
J 0
(700 4150);
DISPLAY 0.617021 (700 4150);
PAINT AQUA (700 4150);
FORCEPROP 1 LASTPIN (1025 4150) $PN 2
J 0
(987 4162);
DISPLAY 0.617021 (987 4162);
PAINT ORANGE (987 4162);
FORCEPROP 1 LAST VALUE 22.1
J 2
(1125 4150);
DISPLAY 0.617021 (1125 4150);
PAINT SKYBLUE (1125 4150);
FORCEPROP 1 LASTPIN (825 4150) $PN 1
J 0
(837 4162);
DISPLAY 0.617021 (837 4162);
PAINT ORANGE (837 4162);
FORCEPROP 1 LAST TOLERANCE 1.0%
J 2
(1225 4150);
DISPLAY 0.617021 (1225 4150);
PAINT SKYBLUE (1225 4150);
FORCEPROP 1 LAST PATH I22
J 0
(875 4300);
DISPLAY 0.978723 (875 4300);
PAINT WHITE (875 4300);
DISPLAY INVISIBLE (875 4300);
FORCEPROP 2 LAST BOM_COST SM_CONTROLLER
J 0
(1200 4200);
DISPLAY 1.021277 (1200 4200);
PAINT ORANGE (1200 4200);
DISPLAY INVISIBLE (1200 4200);
FORCEPROP 2 LAST ROOM BMC
J 0
(1200 4150);
DISPLAY 1.021277 (1200 4150);
PAINT ORANGE (1200 4150);
DISPLAY INVISIBLE (1200 4150);
FORCEPROP 2 LAST CDS_LIB mstr_discrete
J 0
(925 4150);
PAINT ORANGE (925 4150);
DISPLAY INVISIBLE (925 4150);
FORCEPROP 2 LAST SEC_TYPE 0402
J 0
(875 4350);
DISPLAY 1.021277 (875 4350);
PAINT ORANGE (875 4350);
DISPLAY INVISIBLE (875 4350);
FORCEPROP 2 LAST SEC 1
J 0
(875 4350);
DISPLAY 0.680851 (875 4350);
PAINT MONO (875 4350);
DISPLAY INVISIBLE (875 4350);
FORCEPROP 1 LAST PART_NUMBER G21796-250
J 0
(875 4250);
DISPLAY 0.978723 (875 4250);
PAINT BLUE (875 4250);
DISPLAY INVISIBLE (875 4250);
FORCEPROP 1 LAST PACK_TYPE 0402
J 0
(1175 4000);
DISPLAY 0.978723 (1175 4000);
PAINT SKYBLUE (1175 4000);
DISPLAY INVISIBLE (1175 4000);
FORCEPROP 1 LAST WATTAGE 1/16W
J 2
(900 4000);
DISPLAY 0.978723 (900 4000);
PAINT SKYBLUE (900 4000);
DISPLAY INVISIBLE (900 4000);
FORCEPROP 0 LAST CDS_SEC 1
J 0
(1200 4150);
PAINT MONO (1200 4150);
DISPLAY INVISIBLE (1200 4150);
FORCEPROP 1 LAST MATERIAL CHIP
J 2
(750 4100);
DISPLAY 0.617021 (750 4100);
PAINT SKYBLUE (750 4100);
DISPLAY INVISIBLE (750 4100);
FORCEPROP 2 LAST CDS_LOCATION R25W89
J 0
(875 4100);
DISPLAY 0.617021 (875 4100);
PAINT AQUA (875 4100);
DISPLAY INVISIBLE (875 4100);
FORCEADD RES..1
(875 4000);
FORCEPROP 1 LASTPIN (775 4000) $PN 1
J 0
(787 4012);
DISPLAY 0.617021 (787 4012);
PAINT ORANGE (787 4012);
FORCEPROP 1 LAST TOLERANCE 1.0%
J 2
(1175 4000);
DISPLAY 0.617021 (1175 4000);
PAINT SKYBLUE (1175 4000);
FORCEPROP 1 LAST VALUE 22.1
J 0
(975 4000);
DISPLAY 0.617021 (975 4000);
PAINT SKYBLUE (975 4000);
FORCEPROP 1 LASTPIN (975 4000) $PN 2
J 0
(937 4012);
DISPLAY 0.617021 (937 4012);
PAINT ORANGE (937 4012);
FORCEPROP 1 LAST LOCATION R25W85
J 0
(775 3950);
DISPLAY 0.617021 (775 3950);
PAINT AQUA (775 3950);
FORCEPROP 1 LAST MATERIAL CHIP
J 2
(725 4025);
DISPLAY 0.617021 (725 4025);
PAINT SKYBLUE (725 4025);
DISPLAY INVISIBLE (725 4025);
FORCEPROP 0 LAST CDS_SEC 1
J 0
(1075 4000);
PAINT MONO (1075 4000);
DISPLAY INVISIBLE (1075 4000);
FORCEPROP 1 LAST WATTAGE 1/16W
J 2
(825 4025);
DISPLAY 0.978723 (825 4025);
PAINT SKYBLUE (825 4025);
DISPLAY INVISIBLE (825 4025);
FORCEPROP 2 LAST ROOM BMC
J 0
(1075 4050);
DISPLAY 1.021277 (1075 4050);
PAINT ORANGE (1075 4050);
DISPLAY INVISIBLE (1075 4050);
FORCEPROP 2 LAST CDS_LIB mstr_discrete
J 0
(875 4000);
PAINT ORANGE (875 4000);
DISPLAY INVISIBLE (875 4000);
FORCEPROP 1 LAST PACK_TYPE 0402
J 0
(1125 3850);
DISPLAY 0.978723 (1125 3850);
PAINT SKYBLUE (1125 3850);
DISPLAY INVISIBLE (1125 3850);
FORCEPROP 1 LAST PART_NUMBER G21796-250
J 0
(825 4100);
DISPLAY 0.978723 (825 4100);
PAINT BLUE (825 4100);
DISPLAY INVISIBLE (825 4100);
FORCEPROP 2 LAST SEC 1
J 0
(825 4200);
DISPLAY 0.680851 (825 4200);
PAINT MONO (825 4200);
DISPLAY INVISIBLE (825 4200);
FORCEPROP 2 LAST SEC_TYPE 0402
J 0
(825 4200);
DISPLAY 1.021277 (825 4200);
PAINT ORANGE (825 4200);
DISPLAY INVISIBLE (825 4200);
FORCEPROP 2 LAST BOM_COST SM_CONTROLLER
J 0
(1075 4100);
DISPLAY 1.021277 (1075 4100);
PAINT ORANGE (1075 4100);
DISPLAY INVISIBLE (1075 4100);
FORCEPROP 1 LAST PATH I23
J 0
(825 4150);
DISPLAY 0.978723 (825 4150);
PAINT WHITE (825 4150);
DISPLAY INVISIBLE (825 4150);
FORCEPROP 2 LAST CDS_LOCATION R25W85
J 0
(825 3950);
DISPLAY 0.617021 (825 3950);
PAINT AQUA (825 3950);
DISPLAY INVISIBLE (825 3950);
FORCEADD RES..1
(875 3750);
FORCEPROP 1 LAST VALUE 22.1
J 0
(975 3750);
DISPLAY 0.617021 (975 3750);
PAINT SKYBLUE (975 3750);
FORCEPROP 1 LASTPIN (975 3750) $PN 2
J 0
(937 3762);
DISPLAY 0.617021 (937 3762);
PAINT ORANGE (937 3762);
FORCEPROP 1 LASTPIN (775 3750) $PN 1
J 0
(787 3762);
DISPLAY 0.617021 (787 3762);
PAINT ORANGE (787 3762);
FORCEPROP 1 LAST TOLERANCE 1.0%
J 2
(1175 3750);
DISPLAY 0.617021 (1175 3750);
PAINT SKYBLUE (1175 3750);
FORCEPROP 1 LAST LOCATION R25W86
J 0
(600 3750);
DISPLAY 0.617021 (600 3750);
PAINT AQUA (600 3750);
FORCEPROP 2 LAST BOM_COST SM_CONTROLLER
J 0
(1075 3850);
DISPLAY 1.021277 (1075 3850);
PAINT ORANGE (1075 3850);
DISPLAY INVISIBLE (1075 3850);
FORCEPROP 2 LAST ROOM BMC
J 0
(1075 3800);
DISPLAY 1.021277 (1075 3800);
PAINT ORANGE (1075 3800);
DISPLAY INVISIBLE (1075 3800);
FORCEPROP 2 LAST CDS_LIB mstr_discrete
J 0
(875 3750);
PAINT ORANGE (875 3750);
DISPLAY INVISIBLE (875 3750);
FORCEPROP 1 LAST PACK_TYPE 0402
J 0
(1125 3600);
DISPLAY 0.978723 (1125 3600);
PAINT SKYBLUE (1125 3600);
DISPLAY INVISIBLE (1125 3600);
FORCEPROP 2 LAST SEC_TYPE 0402
J 0
(825 3950);
DISPLAY 1.021277 (825 3950);
PAINT ORANGE (825 3950);
DISPLAY INVISIBLE (825 3950);
FORCEPROP 2 LAST SEC 1
J 0
(825 3950);
DISPLAY 0.680851 (825 3950);
PAINT MONO (825 3950);
DISPLAY INVISIBLE (825 3950);
FORCEPROP 1 LAST PART_NUMBER G21796-250
J 0
(825 3850);
DISPLAY 0.978723 (825 3850);
PAINT BLUE (825 3850);
DISPLAY INVISIBLE (825 3850);
FORCEPROP 1 LAST WATTAGE 1/16W
J 2
(850 3600);
DISPLAY 0.978723 (850 3600);
PAINT SKYBLUE (850 3600);
DISPLAY INVISIBLE (850 3600);
FORCEPROP 0 LAST CDS_SEC 1
J 0
(1075 3800);
PAINT MONO (1075 3800);
DISPLAY INVISIBLE (1075 3800);
FORCEPROP 1 LAST MATERIAL CHIP
J 2
(1175 3700);
DISPLAY 0.617021 (1175 3700);
PAINT SKYBLUE (1175 3700);
DISPLAY INVISIBLE (1175 3700);
FORCEPROP 1 LAST PATH I24
J 0
(825 3900);
DISPLAY 0.978723 (825 3900);
PAINT WHITE (825 3900);
DISPLAY INVISIBLE (825 3900);
FORCEPROP 2 LAST CDS_LOCATION R25W86
J 0
(825 3700);
DISPLAY 0.617021 (825 3700);
PAINT AQUA (825 3700);
DISPLAY INVISIBLE (825 3700);
FORCEADD RES..1
(875 3800);
FORCEPROP 1 LAST VALUE 22.1
J 0
(975 3800);
DISPLAY 0.617021 (975 3800);
PAINT SKYBLUE (975 3800);
FORCEPROP 1 LASTPIN (775 3800) $PN 1
J 0
(787 3812);
DISPLAY 0.617021 (787 3812);
PAINT ORANGE (787 3812);
FORCEPROP 1 LASTPIN (975 3800) $PN 2
J 0
(937 3812);
DISPLAY 0.617021 (937 3812);
PAINT ORANGE (937 3812);
FORCEPROP 1 LAST TOLERANCE 1.0%
J 2
(1175 3800);
DISPLAY 0.617021 (1175 3800);
PAINT SKYBLUE (1175 3800);
FORCEPROP 1 LAST LOCATION R25W87
J 0
(600 3800);
DISPLAY 0.617021 (600 3800);
PAINT AQUA (600 3800);
FORCEPROP 1 LAST MATERIAL CHIP
J 2
(1225 3850);
DISPLAY 0.617021 (1225 3850);
PAINT SKYBLUE (1225 3850);
DISPLAY INVISIBLE (1225 3850);
FORCEPROP 0 LAST CDS_SEC 1
J 0
(1225 3900);
PAINT MONO (1225 3900);
DISPLAY INVISIBLE (1225 3900);
FORCEPROP 1 LAST WATTAGE 1/16W
J 2
(850 3650);
DISPLAY 0.978723 (850 3650);
PAINT SKYBLUE (850 3650);
DISPLAY INVISIBLE (850 3650);
FORCEPROP 2 LAST ROOM BMC
J 0
(825 3900);
DISPLAY 1.021277 (825 3900);
PAINT ORANGE (825 3900);
DISPLAY INVISIBLE (825 3900);
FORCEPROP 2 LAST BOM_COST SM_CONTROLLER
J 0
(825 3950);
DISPLAY 1.021277 (825 3950);
PAINT ORANGE (825 3950);
DISPLAY INVISIBLE (825 3950);
FORCEPROP 1 LAST PART_NUMBER G21796-250
J 0
(825 3900);
DISPLAY 0.978723 (825 3900);
PAINT BLUE (825 3900);
DISPLAY INVISIBLE (825 3900);
FORCEPROP 2 LAST SEC 1
J 0
(825 4000);
DISPLAY 0.680851 (825 4000);
PAINT MONO (825 4000);
DISPLAY INVISIBLE (825 4000);
FORCEPROP 2 LAST SEC_TYPE 0402
J 0
(825 4000);
DISPLAY 1.021277 (825 4000);
PAINT ORANGE (825 4000);
DISPLAY INVISIBLE (825 4000);
FORCEPROP 2 LAST CDS_LIB mstr_discrete
J 0
(875 3800);
PAINT ORANGE (875 3800);
DISPLAY INVISIBLE (875 3800);
FORCEPROP 1 LAST PACK_TYPE 0402
J 0
(1125 3650);
DISPLAY 0.978723 (1125 3650);
PAINT SKYBLUE (1125 3650);
DISPLAY INVISIBLE (1125 3650);
FORCEPROP 1 LAST PATH I25
J 0
(825 3950);
DISPLAY 0.978723 (825 3950);
PAINT WHITE (825 3950);
DISPLAY INVISIBLE (825 3950);
FORCEPROP 2 LAST CDS_LOCATION R25W87
J 0
(825 3850);
DISPLAY 0.617021 (825 3850);
PAINT AQUA (825 3850);
DISPLAY INVISIBLE (825 3850);
FORCEADD OFFPAGE..4
(1050 3100);
FORCEPROP 2 LAST $XR1 165 
J 0
(1356 3100);
DISPLAY 0.638298 (1356 3100);
PAINT MONO (1356 3100);
FORCEPROP 2 LAST $XR0 169 
J 0
(1236 3100);
DISPLAY 0.638298 (1236 3100);
PAINT MONO (1236 3100);
FORCEPROP 2 LAST CDS_LIB mstr_standard
J 0
(1050 3100);
PAINT MONO (1050 3100);
DISPLAY INVISIBLE (1050 3100);
FORCEPROP 2 LAST PATH I26
J 0
(1225 3175);
DISPLAY 1.021277 (1225 3175);
PAINT ORANGE (1225 3175);
DISPLAY INVISIBLE (1225 3175);
FORCEPROP 1 LAST OFFPAGE TRUE
J 0
(1375 2975);
DISPLAY 0.872340 (1375 2975);
PAINT GREEN (1375 2975);
DISPLAY INVISIBLE (1375 2975);
FORCEPROP 1 LAST COMMENT_BODY TRUE
J 0
(1025 3000);
DISPLAY 0.872340 (1025 3000);
PAINT GREEN (1025 3000);
DISPLAY INVISIBLE (1025 3000);
FORCEADD OFFPAGE..4
(1050 3200);
FORCEPROP 2 LAST $XR1 165 
J 0
(1356 3200);
DISPLAY 0.638298 (1356 3200);
PAINT MONO (1356 3200);
FORCEPROP 2 LAST $XR0 169 
J 0
(1236 3200);
DISPLAY 0.638298 (1236 3200);
PAINT MONO (1236 3200);
FORCEPROP 2 LAST CDS_LIB mstr_standard
J 0
(1050 3200);
PAINT MONO (1050 3200);
DISPLAY INVISIBLE (1050 3200);
FORCEPROP 2 LAST PATH I27
J 0
(1225 3275);
DISPLAY 1.021277 (1225 3275);
PAINT ORANGE (1225 3275);
DISPLAY INVISIBLE (1225 3275);
FORCEPROP 1 LAST OFFPAGE TRUE
J 0
(1375 3075);
DISPLAY 0.872340 (1375 3075);
PAINT GREEN (1375 3075);
DISPLAY INVISIBLE (1375 3075);
FORCEPROP 1 LAST COMMENT_BODY TRUE
J 0
(1025 3100);
DISPLAY 0.872340 (1025 3100);
PAINT GREEN (1025 3100);
DISPLAY INVISIBLE (1025 3100);
FORCEADD OFFPAGE..4
(1050 3150);
FORCEPROP 2 LAST $XR1 165 
J 0
(1356 3150);
DISPLAY 0.638298 (1356 3150);
PAINT MONO (1356 3150);
FORCEPROP 2 LAST $XR0 169 
J 0
(1236 3150);
DISPLAY 0.638298 (1236 3150);
PAINT MONO (1236 3150);
FORCEPROP 2 LAST CDS_LIB mstr_standard
J 0
(1050 3150);
PAINT MONO (1050 3150);
DISPLAY INVISIBLE (1050 3150);
FORCEPROP 2 LAST PATH I28
J 0
(1225 3225);
DISPLAY 1.021277 (1225 3225);
PAINT ORANGE (1225 3225);
DISPLAY INVISIBLE (1225 3225);
FORCEPROP 1 LAST OFFPAGE TRUE
J 0
(1375 3025);
DISPLAY 0.872340 (1375 3025);
PAINT GREEN (1375 3025);
DISPLAY INVISIBLE (1375 3025);
FORCEPROP 1 LAST COMMENT_BODY TRUE
J 0
(1025 3050);
DISPLAY 0.872340 (1025 3050);
PAINT GREEN (1025 3050);
DISPLAY INVISIBLE (1025 3050);
FORCEADD OFFPAGE..4
(1050 3050);
FORCEPROP 2 LAST $XR1 165 
J 0
(1356 3050);
DISPLAY 0.638298 (1356 3050);
PAINT MONO (1356 3050);
FORCEPROP 2 LAST $XR0 169 
J 0
(1236 3050);
DISPLAY 0.638298 (1236 3050);
PAINT MONO (1236 3050);
FORCEPROP 2 LAST CDS_LIB mstr_standard
J 0
(1050 3050);
PAINT MONO (1050 3050);
DISPLAY INVISIBLE (1050 3050);
FORCEPROP 2 LAST PATH I29
J 0
(1225 3125);
DISPLAY 1.021277 (1225 3125);
PAINT ORANGE (1225 3125);
DISPLAY INVISIBLE (1225 3125);
FORCEPROP 1 LAST OFFPAGE TRUE
J 0
(1375 2925);
DISPLAY 0.872340 (1375 2925);
PAINT GREEN (1375 2925);
DISPLAY INVISIBLE (1375 2925);
FORCEPROP 1 LAST COMMENT_BODY TRUE
J 0
(1025 2950);
DISPLAY 0.872340 (1025 2950);
PAINT GREEN (1025 2950);
DISPLAY INVISIBLE (1025 2950);
FORCEADD RES..2
(2200 4750);
FORCEPROP 1 LASTPIN (2200 4650) $PN 2
J 0
(2205 4660);
DISPLAY 0.617021 (2205 4660);
PAINT ORANGE (2205 4660);
FORCEPROP 1 LASTPIN (2200 4850) $PN 1
J 0
(2205 4812);
DISPLAY 0.617021 (2205 4812);
PAINT ORANGE (2205 4812);
FORCEPROP 1 LAST TOLERANCE 1%
J 0
(2245 4775);
DISPLAY 0.617021 (2245 4775);
PAINT SKYBLUE (2245 4775);
FORCEPROP 1 LAST PACK_TYPE 0402
J 0
(2240 4575);
DISPLAY 0.617021 (2240 4575);
PAINT SKYBLUE (2240 4575);
FORCEPROP 1 LAST PART_NUMBER G21796-016
J 0
(2240 4625);
DISPLAY 0.617021 (2240 4625);
PAINT BLUE (2240 4625);
FORCEPROP 1 LAST MATERIAL CHIP
J 0
(2240 4675);
DISPLAY 0.617021 (2240 4675);
PAINT SKYBLUE (2240 4675);
FORCEPROP 1 LAST WATTAGE 1/16W
J 0
(2240 4725);
DISPLAY 0.617021 (2240 4725);
PAINT SKYBLUE (2240 4725);
FORCEPROP 1 LAST VALUE 10.0K
J 0
(2245 4825);
DISPLAY 0.617021 (2245 4825);
PAINT SKYBLUE (2245 4825);
FORCEPROP 1 LAST LOCATION R25W92
J 0
(2245 4875);
DISPLAY 0.617021 (2245 4875);
PAINT AQUA (2245 4875);
FORCEPROP 0 LAST CDS_SEC 1
J 0
(2250 4925);
PAINT MONO (2250 4925);
DISPLAY INVISIBLE (2250 4925);
FORCEPROP 2 LAST CDS_LIB mstr_discrete
J 0
(2200 4750);
PAINT ORANGE (2200 4750);
DISPLAY INVISIBLE (2200 4750);
FORCEPROP 2 LAST SEC_TYPE 0402
J 0
(2250 4975);
DISPLAY 1.021277 (2250 4975);
PAINT ORANGE (2250 4975);
DISPLAY INVISIBLE (2250 4975);
FORCEPROP 2 LAST BOM_COST SM_CONTROLLER
J 0
(2250 4975);
DISPLAY 1.021277 (2250 4975);
PAINT ORANGE (2250 4975);
DISPLAY INVISIBLE (2250 4975);
FORCEPROP 2 LAST SEC 1
J 0
(2250 4975);
DISPLAY 0.680851 (2250 4975);
PAINT MONO (2250 4975);
DISPLAY INVISIBLE (2250 4975);
FORCEPROP 2 LAST ROOM BMC
J 0
(2250 4925);
DISPLAY 1.021277 (2250 4925);
PAINT ORANGE (2250 4925);
DISPLAY INVISIBLE (2250 4925);
FORCEPROP 1 LAST PATH I3
J 0
(2250 4925);
DISPLAY 0.978723 (2250 4925);
PAINT WHITE (2250 4925);
DISPLAY INVISIBLE (2250 4925);
FORCEPROP 2 LAST CDS_LOCATION R25W92
J 0
(2245 4875);
DISPLAY 0.617021 (2245 4875);
PAINT AQUA (2245 4875);
DISPLAY INVISIBLE (2245 4875);
FORCEADD OFFPAGE..4
(1050 3000);
FORCEPROP 2 LAST $XR1 165 
J 0
(1356 3000);
DISPLAY 0.638298 (1356 3000);
PAINT MONO (1356 3000);
FORCEPROP 2 LAST $XR0 169 
J 0
(1236 3000);
DISPLAY 0.638298 (1236 3000);
PAINT MONO (1236 3000);
FORCEPROP 2 LAST CDS_LIB mstr_standard
J 0
(1050 3000);
PAINT MONO (1050 3000);
DISPLAY INVISIBLE (1050 3000);
FORCEPROP 2 LAST PATH I30
J 0
(1225 3075);
DISPLAY 1.021277 (1225 3075);
PAINT ORANGE (1225 3075);
DISPLAY INVISIBLE (1225 3075);
FORCEPROP 1 LAST OFFPAGE TRUE
J 0
(1375 2875);
DISPLAY 0.872340 (1375 2875);
PAINT GREEN (1375 2875);
DISPLAY INVISIBLE (1375 2875);
FORCEPROP 1 LAST COMMENT_BODY TRUE
J 0
(1025 2900);
DISPLAY 0.872340 (1025 2900);
PAINT GREEN (1025 2900);
DISPLAY INVISIBLE (1025 2900);
FORCEADD OFFPAGE..4
(1050 2950);
FORCEPROP 2 LAST $XR1 165 
J 0
(1356 2950);
DISPLAY 0.638298 (1356 2950);
PAINT MONO (1356 2950);
FORCEPROP 2 LAST $XR0 169 
J 0
(1236 2950);
DISPLAY 0.638298 (1236 2950);
PAINT MONO (1236 2950);
FORCEPROP 2 LAST CDS_LIB mstr_standard
J 0
(1050 2950);
PAINT MONO (1050 2950);
DISPLAY INVISIBLE (1050 2950);
FORCEPROP 2 LAST PATH I31
J 0
(1225 3025);
DISPLAY 1.021277 (1225 3025);
PAINT ORANGE (1225 3025);
DISPLAY INVISIBLE (1225 3025);
FORCEPROP 1 LAST OFFPAGE TRUE
J 0
(1375 2825);
DISPLAY 0.872340 (1375 2825);
PAINT GREEN (1375 2825);
DISPLAY INVISIBLE (1375 2825);
FORCEPROP 1 LAST COMMENT_BODY TRUE
J 0
(1025 2850);
DISPLAY 0.872340 (1025 2850);
PAINT GREEN (1025 2850);
DISPLAY INVISIBLE (1025 2850);
FORCEADD OFFPAGE..4
(1050 2900);
FORCEPROP 2 LAST $XR1 165 
J 0
(1356 2900);
DISPLAY 0.638298 (1356 2900);
PAINT MONO (1356 2900);
FORCEPROP 2 LAST $XR0 169 
J 0
(1236 2900);
DISPLAY 0.638298 (1236 2900);
PAINT MONO (1236 2900);
FORCEPROP 2 LAST CDS_LIB mstr_standard
J 0
(1050 2900);
PAINT MONO (1050 2900);
DISPLAY INVISIBLE (1050 2900);
FORCEPROP 2 LAST PATH I32
J 0
(1225 2975);
DISPLAY 1.021277 (1225 2975);
PAINT ORANGE (1225 2975);
DISPLAY INVISIBLE (1225 2975);
FORCEPROP 1 LAST OFFPAGE TRUE
J 0
(1375 2775);
DISPLAY 0.872340 (1375 2775);
PAINT GREEN (1375 2775);
DISPLAY INVISIBLE (1375 2775);
FORCEPROP 1 LAST COMMENT_BODY TRUE
J 0
(1025 2800);
DISPLAY 0.872340 (1025 2800);
PAINT GREEN (1025 2800);
DISPLAY INVISIBLE (1025 2800);
FORCEADD OFFPAGE..4
(1050 2850);
FORCEPROP 2 LAST $XR1 165 
J 0
(1356 2850);
DISPLAY 0.638298 (1356 2850);
PAINT MONO (1356 2850);
FORCEPROP 2 LAST $XR0 169 
J 0
(1236 2850);
DISPLAY 0.638298 (1236 2850);
PAINT MONO (1236 2850);
FORCEPROP 2 LAST PATH I33
J 0
(1225 2925);
DISPLAY 1.021277 (1225 2925);
PAINT ORANGE (1225 2925);
DISPLAY INVISIBLE (1225 2925);
FORCEPROP 2 LAST CDS_LIB mstr_standard
J 0
(1050 2850);
PAINT MONO (1050 2850);
DISPLAY INVISIBLE (1050 2850);
FORCEPROP 1 LAST OFFPAGE TRUE
J 0
(1375 2725);
DISPLAY 0.872340 (1375 2725);
PAINT GREEN (1375 2725);
DISPLAY INVISIBLE (1375 2725);
FORCEPROP 1 LAST COMMENT_BODY TRUE
J 0
(1025 2750);
DISPLAY 0.872340 (1025 2750);
PAINT GREEN (1025 2750);
DISPLAY INVISIBLE (1025 2750);
FORCEADD OFFPAGE..2
(1075 2400);
FORCEPROP 2 LAST $XR1 161 
J 0
(1384 2400);
DISPLAY 0.638298 (1384 2400);
PAINT MONO (1384 2400);
FORCEPROP 2 LAST $XR0 120 
J 0
(1264 2400);
DISPLAY 0.638298 (1264 2400);
PAINT MONO (1264 2400);
FORCEPROP 2 LAST CDS_LIB mstr_standard
J 0
(1075 2400);
PAINT ORANGE (1075 2400);
DISPLAY INVISIBLE (1075 2400);
FORCEPROP 2 LAST PATH I34
J 0
(1400 2450);
DISPLAY 1.021277 (1400 2450);
PAINT ORANGE (1400 2450);
DISPLAY INVISIBLE (1400 2450);
FORCEPROP 1 LAST OFFPAGE TRUE
J 0
(1400 2275);
DISPLAY 0.872340 (1400 2275);
PAINT GREEN (1400 2275);
DISPLAY INVISIBLE (1400 2275);
FORCEPROP 1 LAST COMMENT_BODY TRUE
J 0
(1030 2305);
DISPLAY 0.872340 (1030 2305);
PAINT GREEN (1030 2305);
DISPLAY INVISIBLE (1030 2305);
FORCEADD OFFPAGE..2
(1075 2450);
FORCEPROP 2 LAST $XR1 161 
J 0
(1384 2450);
DISPLAY 0.638298 (1384 2450);
PAINT MONO (1384 2450);
FORCEPROP 2 LAST $XR0 120 
J 0
(1264 2450);
DISPLAY 0.638298 (1264 2450);
PAINT MONO (1264 2450);
FORCEPROP 2 LAST PATH I35
J 0
(1400 2500);
DISPLAY 1.021277 (1400 2500);
PAINT ORANGE (1400 2500);
DISPLAY INVISIBLE (1400 2500);
FORCEPROP 2 LAST CDS_LIB mstr_standard
J 0
(1075 2450);
PAINT ORANGE (1075 2450);
DISPLAY INVISIBLE (1075 2450);
FORCEPROP 1 LAST OFFPAGE TRUE
J 0
(1400 2325);
DISPLAY 0.872340 (1400 2325);
PAINT GREEN (1400 2325);
DISPLAY INVISIBLE (1400 2325);
FORCEPROP 1 LAST COMMENT_BODY TRUE
J 0
(1030 2355);
DISPLAY 0.872340 (1030 2355);
PAINT GREEN (1030 2355);
DISPLAY INVISIBLE (1030 2355);
FORCEADD CAP..1
R 1
(2000 2300);
FORCEPROP 1 LAST TOLERANCE 10%
J 0
(1825 2350);
DISPLAY 0.617021 (1825 2350);
PAINT SKYBLUE (1825 2350);
FORCEPROP 1 LAST LOCATION C25W7
J 0
(1825 2400);
DISPLAY 0.617021 (1825 2400);
PAINT AQUA (1825 2400);
FORCEPROP 1 LAST MATERIAL EMPTY
J 0
(2000 2400);
DISPLAY 0.617021 (2000 2400);
PAINT RED (2000 2400);
FORCEPROP 1 LAST PACK_TYPE 0402
J 0
(1950 2000);
DISPLAY 0.617021 (1950 2000);
PAINT SKYBLUE (1950 2000);
FORCEPROP 1 LAST VOLTAGE 16V
J 0
(2000 2350);
DISPLAY 0.617021 (2000 2350);
PAINT SKYBLUE (2000 2350);
FORCEPROP 1 LAST PART_NUMBER A36096-030
J 0
(2100 2250);
DISPLAY 0.617021 (2100 2250);
PAINT BLUE (2100 2250);
FORCEPROP 1 LAST VALUE 0.1UF
J 0
(1825 2375);
DISPLAY 0.617021 (1825 2375);
PAINT SKYBLUE (1825 2375);
FORCEPROP 1 LASTPIN (2100 2300) $PN 2
R 1
J 0
(2120 2310);
DISPLAY 0.617021 (2120 2310);
PAINT ORANGE (2120 2310);
DISPLAY INVISIBLE (2120 2310);
FORCEPROP 2 LAST CDS_LIB mstr_discrete
R 1
J 0
(2000 2300);
PAINT ORANGE (2000 2300);
DISPLAY INVISIBLE (2000 2300);
FORCEPROP 1 LASTPIN (1900 2300) $PN 1
R 1
J 0
(1920 2310);
DISPLAY 0.617021 (1920 2310);
PAINT ORANGE (1920 2310);
DISPLAY INVISIBLE (1920 2310);
FORCEPROP 2 LAST ROOM BMC
R 1
J 0
(1850 2350);
DISPLAY 1.021277 (1850 2350);
PAINT ORANGE (1850 2350);
DISPLAY INVISIBLE (1850 2350);
FORCEPROP 2 LAST BOM_COST SM_CONTROLLER
R 1
J 0
(1800 2350);
DISPLAY 1.021277 (1800 2350);
PAINT ORANGE (1800 2350);
DISPLAY INVISIBLE (1800 2350);
FORCEPROP 2 LAST $SEC 1
R 1
J 0
(1800 2350);
PAINT MONO (1800 2350);
DISPLAY INVISIBLE (1800 2350);
FORCEPROP 2 LAST CDS_SEC 1
R 1
J 0
(1800 2350);
PAINT MONO (1800 2350);
DISPLAY INVISIBLE (1800 2350);
FORCEPROP 1 LAST PATH I36
R 1
J 0
(1850 2350);
DISPLAY 0.978723 (1850 2350);
PAINT WHITE (1850 2350);
DISPLAY INVISIBLE (1850 2350);
FORCEPROP 0 LAST CDS_LOCATION C25W7
R 1
J 0
(1850 2350);
PAINT MONO (1850 2350);
DISPLAY INVISIBLE (1850 2350);
FORCEADD GND..1
R 2
(2325 1850);
FORCEPROP 3 LASTPIN (2325 1900) SIG_NAME GND\g
J 0
(2335 1910);
DISPLAY 0.659574 (2335 1910);
PAINT MONO (2335 1910);
DISPLAY INVISIBLE (2335 1910);
FORCEPROP 1 LAST VOLTAGE 0.0V
J 2
(2370 1807);
DISPLAY 0.340426 (2370 1807);
PAINT GREEN (2370 1807);
DISPLAY INVISIBLE (2370 1807);
FORCEPROP 1 LAST SIZE 1B
J 2
(2250 1800);
DISPLAY 0.872340 (2250 1800);
PAINT AQUA (2250 1800);
DISPLAY INVISIBLE (2250 1800);
FORCEPROP 2 LAST CDS_LIB mstr_symbols
J 2
(2325 1850);
PAINT MONO (2325 1850);
DISPLAY INVISIBLE (2325 1850);
FORCEPROP 1 LAST PATH I37
J 2
(2250 1850);
DISPLAY 0.872340 (2250 1850);
PAINT AQUA (2250 1850);
DISPLAY INVISIBLE (2250 1850);
FORCEPROP 1 LAST BODY_TYPE PLUMBING
J 2
(2370 1807);
DISPLAY 0.340426 (2370 1807);
PAINT GREEN (2370 1807);
DISPLAY INVISIBLE (2370 1807);
FORCEPROP 1 LAST HDL_POWER GND
J 2
(2325 2000);
DISPLAY 0.872340 (2325 2000);
PAINT GREEN (2325 2000);
DISPLAY INVISIBLE (2325 2000);
FORCEADD CAP..2
(2000 1950);
FORCEPROP 1 LAST VOLTAGE 16V
J 0
(2150 1900);
DISPLAY 0.617021 (2150 1900);
PAINT SKYBLUE (2150 1900);
FORCEPROP 1 LAST LOCATION C25W8
J 1
(2000 2050);
DISPLAY 0.617021 (2000 2050);
PAINT AQUA (2000 2050);
FORCEPROP 1 LASTPIN (1900 1950) $PN 1
J 0
(1890 1965);
DISPLAY 0.617021 (1890 1965);
PAINT ORANGE (1890 1965);
FORCEPROP 1 LAST VALUE 0.1UF
J 2
(1900 1850);
DISPLAY 0.617021 (1900 1850);
PAINT SKYBLUE (1900 1850);
FORCEPROP 1 LAST TOLERANCE 10%
J 2
(2250 1850);
DISPLAY 0.617021 (2250 1850);
PAINT SKYBLUE (2250 1850);
FORCEPROP 1 LASTPIN (2100 1950) $PN 2
J 0
(2085 1965);
DISPLAY 0.617021 (2085 1965);
PAINT ORANGE (2085 1965);
FORCEPROP 1 LAST PART_NUMBER A36096-030
J 1
(2100 1775);
DISPLAY 0.617021 (2100 1775);
PAINT BLUE (2100 1775);
FORCEPROP 1 LAST MATERIAL EMPTY
J 0
(2000 1800);
DISPLAY 0.617021 (2000 1800);
PAINT RED (2000 1800);
FORCEPROP 1 LAST PACK_TYPE 0402
J 1
(1850 1800);
DISPLAY 0.617021 (1850 1800);
PAINT SKYBLUE (1850 1800);
FORCEPROP 2 LAST BOM_COST SM_CONTROLLER
J 0
(1750 2075);
DISPLAY 1.021277 (1750 2075);
PAINT ORANGE (1750 2075);
DISPLAY INVISIBLE (1750 2075);
FORCEPROP 2 LAST ROOM BMC
J 0
(1750 2025);
DISPLAY 1.021277 (1750 2025);
PAINT ORANGE (1750 2025);
DISPLAY INVISIBLE (1750 2025);
FORCEPROP 2 LAST CDS_LIB mstr_discrete
J 0
(2000 1950);
PAINT ORANGE (2000 1950);
DISPLAY INVISIBLE (2000 1950);
FORCEPROP 2 LAST SEC_TYPE 0402
J 0
(2000 2200);
DISPLAY 1.021277 (2000 2200);
PAINT ORANGE (2000 2200);
DISPLAY INVISIBLE (2000 2200);
FORCEPROP 2 LAST SEC 1
J 0
(2000 2200);
DISPLAY 0.680851 (2000 2200);
PAINT MONO (2000 2200);
DISPLAY INVISIBLE (2000 2200);
FORCEPROP 0 LAST CDS_SEC 1
J 0
(1750 2025);
PAINT MONO (1750 2025);
DISPLAY INVISIBLE (1750 2025);
FORCEPROP 1 LAST PATH I38
J 0
(2000 2150);
DISPLAY 0.978723 (2000 2150);
PAINT WHITE (2000 2150);
DISPLAY INVISIBLE (2000 2150);
FORCEPROP 0 LAST CDS_LOCATION C25W8
J 0
(1750 2025);
PAINT MONO (1750 2025);
DISPLAY INVISIBLE (1750 2025);
FORCEADD CAP..2
R 1
(1625 2125);
FORCEPROP 1 LAST PART_NUMBER A36096-030
J 1
(1775 2225);
DISPLAY 0.617021 (1775 2225);
PAINT BLUE (1775 2225);
FORCEPROP 1 LAST MATERIAL EMPTY
J 0
(1725 2050);
DISPLAY 0.617021 (1725 2050);
PAINT RED (1725 2050);
FORCEPROP 1 LAST LOCATION C25W9
J 1
(1475 2125);
DISPLAY 0.617021 (1475 2125);
PAINT AQUA (1475 2125);
FORCEPROP 1 LAST VOLTAGE 16V
J 0
(1350 2075);
DISPLAY 0.617021 (1350 2075);
PAINT SKYBLUE (1350 2075);
FORCEPROP 1 LASTPIN (1625 2025) $PN 1
R 1
J 0
(1610 2015);
DISPLAY 0.617021 (1610 2015);
PAINT ORANGE (1610 2015);
FORCEPROP 1 LAST VALUE 0.1UF
J 2
(1450 2025);
DISPLAY 0.617021 (1450 2025);
PAINT SKYBLUE (1450 2025);
FORCEPROP 1 LAST PACK_TYPE 0402
J 1
(1500 2075);
DISPLAY 0.617021 (1500 2075);
PAINT SKYBLUE (1500 2075);
FORCEPROP 1 LAST TOLERANCE 10%
J 2
(1550 2050);
DISPLAY 0.617021 (1550 2050);
PAINT SKYBLUE (1550 2050);
FORCEPROP 1 LASTPIN (1625 2225) $PN 2
R 1
J 0
(1610 2210);
DISPLAY 0.617021 (1610 2210);
PAINT ORANGE (1610 2210);
FORCEPROP 0 LAST CDS_SEC 1
R 1
J 0
(1425 2125);
PAINT MONO (1425 2125);
DISPLAY INVISIBLE (1425 2125);
FORCEPROP 2 LAST SEC 1
R 1
J 0
(1375 2125);
DISPLAY 0.680851 (1375 2125);
PAINT MONO (1375 2125);
DISPLAY INVISIBLE (1375 2125);
FORCEPROP 2 LAST ROOM BMC
R 1
J 0
(1425 2125);
DISPLAY 1.021277 (1425 2125);
PAINT ORANGE (1425 2125);
DISPLAY INVISIBLE (1425 2125);
FORCEPROP 2 LAST SEC_TYPE 0402
R 1
J 0
(1375 2125);
DISPLAY 1.021277 (1375 2125);
PAINT ORANGE (1375 2125);
DISPLAY INVISIBLE (1375 2125);
FORCEPROP 2 LAST BOM_COST SM_CONTROLLER
R 1
J 0
(1375 2125);
DISPLAY 1.021277 (1375 2125);
PAINT ORANGE (1375 2125);
DISPLAY INVISIBLE (1375 2125);
FORCEPROP 2 LAST CDS_LIB mstr_discrete
R 1
J 0
(1625 2125);
PAINT ORANGE (1625 2125);
DISPLAY INVISIBLE (1625 2125);
FORCEPROP 1 LAST PATH I39
R 1
J 0
(1425 2125);
DISPLAY 0.978723 (1425 2125);
PAINT WHITE (1425 2125);
DISPLAY INVISIBLE (1425 2125);
FORCEPROP 0 LAST CDS_LOCATION C25W9
R 1
J 0
(1425 2125);
PAINT MONO (1425 2125);
DISPLAY INVISIBLE (1425 2125);
FORCEADD RES..2
(1950 4775);
FORCEPROP 1 LASTPIN (1950 4675) $PN 2
J 0
(1955 4685);
DISPLAY 0.617021 (1955 4685);
PAINT ORANGE (1955 4685);
FORCEPROP 1 LAST WATTAGE 1/16W
J 0
(1990 4750);
DISPLAY 0.617021 (1990 4750);
PAINT SKYBLUE (1990 4750);
FORCEPROP 1 LAST VALUE 10.0K
J 0
(1995 4850);
DISPLAY 0.617021 (1995 4850);
PAINT SKYBLUE (1995 4850);
FORCEPROP 1 LAST TOLERANCE 1%
J 0
(1995 4800);
DISPLAY 0.617021 (1995 4800);
PAINT SKYBLUE (1995 4800);
FORCEPROP 1 LASTPIN (1950 4875) $PN 1
J 0
(1955 4837);
DISPLAY 0.617021 (1955 4837);
PAINT ORANGE (1955 4837);
FORCEPROP 1 LAST MATERIAL CHIP
J 0
(1990 4700);
DISPLAY 0.617021 (1990 4700);
PAINT SKYBLUE (1990 4700);
FORCEPROP 1 LAST PART_NUMBER G21796-016
J 0
(1990 4650);
DISPLAY 0.617021 (1990 4650);
PAINT BLUE (1990 4650);
FORCEPROP 1 LAST PACK_TYPE 0402
J 0
(1990 4600);
DISPLAY 0.617021 (1990 4600);
PAINT SKYBLUE (1990 4600);
FORCEPROP 1 LAST LOCATION R25W91
J 0
(1995 4900);
DISPLAY 0.617021 (1995 4900);
PAINT AQUA (1995 4900);
FORCEPROP 1 LAST PATH I4
J 0
(2000 4950);
DISPLAY 0.978723 (2000 4950);
PAINT WHITE (2000 4950);
DISPLAY INVISIBLE (2000 4950);
FORCEPROP 2 LAST SEC_TYPE 0402
J 0
(2000 5000);
DISPLAY 1.021277 (2000 5000);
PAINT ORANGE (2000 5000);
DISPLAY INVISIBLE (2000 5000);
FORCEPROP 2 LAST SEC 1
J 0
(2000 5000);
DISPLAY 0.680851 (2000 5000);
PAINT MONO (2000 5000);
DISPLAY INVISIBLE (2000 5000);
FORCEPROP 2 LAST ROOM BMC
J 0
(2000 4950);
DISPLAY 1.021277 (2000 4950);
PAINT ORANGE (2000 4950);
DISPLAY INVISIBLE (2000 4950);
FORCEPROP 2 LAST BOM_COST SM_CONTROLLER
J 0
(2000 5000);
DISPLAY 1.021277 (2000 5000);
PAINT ORANGE (2000 5000);
DISPLAY INVISIBLE (2000 5000);
FORCEPROP 2 LAST CDS_LIB mstr_discrete
J 0
(1950 4775);
PAINT ORANGE (1950 4775);
DISPLAY INVISIBLE (1950 4775);
FORCEPROP 0 LAST CDS_SEC 1
J 0
(2000 4950);
PAINT MONO (2000 4950);
DISPLAY INVISIBLE (2000 4950);
FORCEPROP 2 LAST CDS_LOCATION R25W91
J 0
(1995 4900);
DISPLAY 0.617021 (1995 4900);
PAINT AQUA (1995 4900);
DISPLAY INVISIBLE (1995 4900);
FORCEADD RES..2
R 6
(775 1925);
FORCEPROP 1 LAST WATTAGE 1/16W
J 0
(815 1921);
DISPLAY 0.617021 (815 1921);
PAINT SKYBLUE (815 1921);
FORCEPROP 1 LAST MATERIAL CHIP
J 0
(815 1971);
DISPLAY 0.617021 (815 1971);
PAINT SKYBLUE (815 1971);
FORCEPROP 1 LAST TOLERANCE 1%
J 0
(820 1871);
DISPLAY 0.617021 (820 1871);
PAINT SKYBLUE (820 1871);
FORCEPROP 1 LASTPIN (775 1825) $PN 1
J 0
(780 1834);
DISPLAY 0.617021 (780 1834);
PAINT ORANGE (780 1834);
FORCEPROP 1 LAST LOCATION R25W57
J 0
(820 1771);
DISPLAY 0.617021 (820 1771);
PAINT AQUA (820 1771);
FORCEPROP 1 LAST VALUE 2.7K
J 0
(820 1821);
DISPLAY 0.617021 (820 1821);
PAINT SKYBLUE (820 1821);
FORCEPROP 1 LAST PACK_TYPE 0402
J 0
(815 2071);
DISPLAY 0.617021 (815 2071);
PAINT SKYBLUE (815 2071);
FORCEPROP 1 LAST PART_NUMBER G21796-344
J 0
(815 2021);
DISPLAY 0.617021 (815 2021);
PAINT BLUE (815 2021);
FORCEPROP 1 LASTPIN (775 2025) $PN 2
J 0
(780 1986);
DISPLAY 0.617021 (780 1986);
PAINT ORANGE (780 1986);
FORCEPROP 0 LAST ROOM BMC
J 0
(825 1671);
DISPLAY 0.617021 (825 1671);
PAINT ORANGE (825 1671);
DISPLAY INVISIBLE (825 1671);
FORCEPROP 0 LAST BOM_COST SM_CONTROLLER
J 0
(825 1552);
DISPLAY 1.021277 (825 1552);
PAINT ORANGE (825 1552);
DISPLAY INVISIBLE (825 1552);
FORCEPROP 2 LAST SEC 1
J 0
(825 1668);
DISPLAY 0.680851 (825 1668);
PAINT MONO (825 1668);
DISPLAY INVISIBLE (825 1668);
FORCEPROP 2 LAST SEC_TYPE 0402
J 0
(825 1652);
DISPLAY 1.021277 (825 1652);
PAINT ORANGE (825 1652);
DISPLAY INVISIBLE (825 1652);
FORCEPROP 2 LAST CDS_LIB mstr_discrete
J 0
(775 1878);
PAINT ORANGE (775 1878);
DISPLAY INVISIBLE (775 1878);
FORCEPROP 0 LAST CDS_SEC 1
J 0
(825 1703);
PAINT MONO (825 1703);
DISPLAY INVISIBLE (825 1703);
FORCEPROP 1 LAST PATH I40
J 0
(825 1750);
DISPLAY 0.978723 (825 1750);
PAINT WHITE (825 1750);
DISPLAY INVISIBLE (825 1750);
FORCEPROP 0 LAST CDS_LOCATION R25W57
J 0
(825 1703);
PAINT MONO (825 1703);
DISPLAY INVISIBLE (825 1703);
FORCEADD GND..1
(775 1675);
FORCEPROP 3 LASTPIN (775 1725) SIG_NAME GND\g
J 0
(785 1735);
DISPLAY 0.659574 (785 1735);
PAINT MONO (785 1735);
DISPLAY INVISIBLE (785 1735);
FORCEPROP 1 LAST SIZE 1B
J 0
(850 1625);
DISPLAY 0.872340 (850 1625);
PAINT AQUA (850 1625);
DISPLAY INVISIBLE (850 1625);
FORCEPROP 2 LAST CDS_LIB mstr_symbols
J 0
(775 1675);
PAINT ORANGE (775 1675);
DISPLAY INVISIBLE (775 1675);
FORCEPROP 1 LAST VOLTAGE 0.0V
J 0
(730 1632);
DISPLAY 0.340426 (730 1632);
PAINT GREEN (730 1632);
DISPLAY INVISIBLE (730 1632);
FORCEPROP 1 LAST PATH I41
J 0
(850 1675);
DISPLAY 0.872340 (850 1675);
PAINT AQUA (850 1675);
DISPLAY INVISIBLE (850 1675);
FORCEPROP 1 LAST BODY_TYPE PLUMBING
J 0
(730 1632);
DISPLAY 0.340426 (730 1632);
PAINT GREEN (730 1632);
DISPLAY INVISIBLE (730 1632);
FORCEPROP 1 LAST HDL_POWER GND
J 0
(775 1825);
DISPLAY 0.872340 (775 1825);
PAINT GREEN (775 1825);
DISPLAY INVISIBLE (775 1825);
FORCEADD RES..2
(-3650 4800);
FORCEPROP 1 LASTPIN (-3650 4900) $PN 1
J 0
(-3645 4862);
DISPLAY 0.617021 (-3645 4862);
PAINT ORANGE (-3645 4862);
FORCEPROP 1 LASTPIN (-3650 4700) $PN 2
J 0
(-3645 4710);
DISPLAY 0.617021 (-3645 4710);
PAINT ORANGE (-3645 4710);
FORCEPROP 1 LAST PART_NUMBER G21796-016
J 0
(-3610 4975);
DISPLAY 0.617021 (-3610 4975);
PAINT BLUE (-3610 4975);
FORCEPROP 1 LAST LOCATION R25W79
J 0
(-3605 4925);
DISPLAY 0.617021 (-3605 4925);
PAINT AQUA (-3605 4925);
FORCEPROP 1 LAST VALUE 10.0K
J 0
(-3605 4875);
DISPLAY 0.617021 (-3605 4875);
PAINT SKYBLUE (-3605 4875);
FORCEPROP 1 LAST TOLERANCE 1%
J 0
(-3605 4825);
DISPLAY 0.617021 (-3605 4825);
PAINT SKYBLUE (-3605 4825);
FORCEPROP 1 LAST WATTAGE 1/16W
J 0
(-3610 4775);
DISPLAY 0.617021 (-3610 4775);
PAINT SKYBLUE (-3610 4775);
FORCEPROP 1 LAST MATERIAL CHIP
J 0
(-3610 4725);
DISPLAY 0.617021 (-3610 4725);
PAINT SKYBLUE (-3610 4725);
FORCEPROP 1 LAST PACK_TYPE 0402
J 0
(-3610 4625);
DISPLAY 0.617021 (-3610 4625);
PAINT SKYBLUE (-3610 4625);
FORCEPROP 2 LAST CDS_LIB mstr_discrete
J 0
(-3650 4800);
PAINT ORANGE (-3650 4800);
DISPLAY INVISIBLE (-3650 4800);
FORCEPROP 2 LAST BOM_COST SM_CONTROLLER
J 0
(-3600 5025);
DISPLAY 1.021277 (-3600 5025);
PAINT ORANGE (-3600 5025);
DISPLAY INVISIBLE (-3600 5025);
FORCEPROP 2 LAST SEC_TYPE 0402
J 0
(-3600 5025);
DISPLAY 1.021277 (-3600 5025);
PAINT ORANGE (-3600 5025);
DISPLAY INVISIBLE (-3600 5025);
FORCEPROP 2 LAST SEC 1
J 0
(-3600 5025);
DISPLAY 0.680851 (-3600 5025);
PAINT MONO (-3600 5025);
DISPLAY INVISIBLE (-3600 5025);
FORCEPROP 2 LAST ROOM BMC
J 0
(-3600 4975);
DISPLAY 1.021277 (-3600 4975);
PAINT ORANGE (-3600 4975);
DISPLAY INVISIBLE (-3600 4975);
FORCEPROP 1 LAST PATH I42
J 0
(-3600 4975);
DISPLAY 0.978723 (-3600 4975);
PAINT WHITE (-3600 4975);
DISPLAY INVISIBLE (-3600 4975);
FORCEPROP 2 LAST CDS_LOCATION R25W79
J 0
(-3605 4925);
DISPLAY 0.617021 (-3605 4925);
PAINT AQUA (-3605 4925);
DISPLAY INVISIBLE (-3605 4925);
FORCEADD RES..2
(-3900 4800);
FORCEPROP 1 LAST TOLERANCE 1%
J 0
(-3855 4825);
DISPLAY 0.617021 (-3855 4825);
PAINT SKYBLUE (-3855 4825);
FORCEPROP 1 LASTPIN (-3900 4700) $PN 2
J 0
(-3895 4710);
DISPLAY 0.617021 (-3895 4710);
PAINT ORANGE (-3895 4710);
FORCEPROP 1 LAST MATERIAL CHIP
J 0
(-3860 4725);
DISPLAY 0.617021 (-3860 4725);
PAINT SKYBLUE (-3860 4725);
FORCEPROP 1 LAST PACK_TYPE 0402
J 0
(-3860 4625);
DISPLAY 0.617021 (-3860 4625);
PAINT SKYBLUE (-3860 4625);
FORCEPROP 1 LASTPIN (-3900 4900) $PN 1
J 0
(-3895 4862);
DISPLAY 0.617021 (-3895 4862);
PAINT ORANGE (-3895 4862);
FORCEPROP 1 LAST WATTAGE 1/16W
J 0
(-3860 4775);
DISPLAY 0.617021 (-3860 4775);
PAINT SKYBLUE (-3860 4775);
FORCEPROP 1 LAST LOCATION R25W80
J 0
(-3855 4925);
DISPLAY 0.617021 (-3855 4925);
PAINT AQUA (-3855 4925);
FORCEPROP 1 LAST VALUE 10.0K
J 0
(-3855 4875);
DISPLAY 0.617021 (-3855 4875);
PAINT SKYBLUE (-3855 4875);
FORCEPROP 1 LAST PART_NUMBER G21796-016
J 0
(-3860 4675);
DISPLAY 0.617021 (-3860 4675);
PAINT BLUE (-3860 4675);
FORCEPROP 2 LAST CDS_LOCATION R25W80
J 0
(-3855 4925);
DISPLAY 0.617021 (-3855 4925);
PAINT AQUA (-3855 4925);
DISPLAY INVISIBLE (-3855 4925);
FORCEPROP 1 LAST PATH I43
J 0
(-3850 4975);
DISPLAY 0.978723 (-3850 4975);
PAINT WHITE (-3850 4975);
DISPLAY INVISIBLE (-3850 4975);
FORCEPROP 2 LAST ROOM BMC
J 0
(-3850 4975);
DISPLAY 1.021277 (-3850 4975);
PAINT ORANGE (-3850 4975);
DISPLAY INVISIBLE (-3850 4975);
FORCEPROP 2 LAST SEC 1
J 0
(-3850 5025);
DISPLAY 0.680851 (-3850 5025);
PAINT MONO (-3850 5025);
DISPLAY INVISIBLE (-3850 5025);
FORCEPROP 2 LAST SEC_TYPE 0402
J 0
(-3850 5025);
DISPLAY 1.021277 (-3850 5025);
PAINT ORANGE (-3850 5025);
DISPLAY INVISIBLE (-3850 5025);
FORCEPROP 2 LAST BOM_COST SM_CONTROLLER
J 0
(-3850 5025);
DISPLAY 1.021277 (-3850 5025);
PAINT ORANGE (-3850 5025);
DISPLAY INVISIBLE (-3850 5025);
FORCEPROP 2 LAST CDS_LIB mstr_discrete
J 0
(-3900 4800);
PAINT ORANGE (-3900 4800);
DISPLAY INVISIBLE (-3900 4800);
FORCEADD P3V3_STBY..1
(-3900 5100);
FORCEPROP 3 LASTPIN (-3900 5050) SIG_NAME P3V3_STBY\g
J 0
(-3890 5060);
DISPLAY 0.659574 (-3890 5060);
PAINT MONO (-3890 5060);
DISPLAY INVISIBLE (-3890 5060);
FORCEPROP 1 LAST HDL_POWER P3V3_STBY
J 0
(-4200 4975);
DISPLAY 0.872340 (-4200 4975);
PAINT ORANGE (-4200 4975);
DISPLAY INVISIBLE (-4200 4975);
FORCEPROP 1 LAST BODY_TYPE PLUMBING
J 0
(-3945 5057);
DISPLAY 0.340426 (-3945 5057);
PAINT GREEN (-3945 5057);
DISPLAY INVISIBLE (-3945 5057);
FORCEPROP 1 LAST PATH I44
J 0
(-3855 5102);
DISPLAY 0.340426 (-3855 5102);
PAINT GREEN (-3855 5102);
DISPLAY INVISIBLE (-3855 5102);
FORCEPROP 1 LAST VOLTAGE 3.3V
J 0
(-3945 5057);
DISPLAY 0.340426 (-3945 5057);
PAINT SKYBLUE (-3945 5057);
DISPLAY INVISIBLE (-3945 5057);
FORCEPROP 2 LAST CDS_LIB mstr_symbols
J 0
(-3900 5100);
PAINT ORANGE (-3900 5100);
DISPLAY INVISIBLE (-3900 5100);
FORCEPROP 1 LAST SIZE 1B
J 0
(-3855 5122);
DISPLAY 0.340426 (-3855 5122);
PAINT GREEN (-3855 5122);
DISPLAY INVISIBLE (-3855 5122);
FORCEADD OFFPAGE..1
(-4775 4450);
FORCEPROP 2 LAST $XR0 101 
J 0
(-5027 4450);
DISPLAY 0.638298 (-5027 4450);
PAINT MONO (-5027 4450);
FORCEPROP 2 LAST PATH I45
J 0
(-5025 4500);
DISPLAY 1.021277 (-5025 4500);
PAINT ORANGE (-5025 4500);
DISPLAY INVISIBLE (-5025 4500);
FORCEPROP 2 LAST CDS_LIB mstr_standard
J 0
(-4775 4450);
PAINT ORANGE (-4775 4450);
DISPLAY INVISIBLE (-4775 4450);
FORCEPROP 1 LAST OFFPAGE TRUE
J 0
(-4450 4325);
DISPLAY 0.872340 (-4450 4325);
PAINT GREEN (-4450 4325);
DISPLAY INVISIBLE (-4450 4325);
FORCEPROP 1 LAST COMMENT_BODY TRUE
J 0
(-4650 4350);
DISPLAY 0.872340 (-4650 4350);
PAINT GREEN (-4650 4350);
DISPLAY INVISIBLE (-4650 4350);
FORCEADD GND..1
(-3525 3600);
FORCEPROP 3 LASTPIN (-3525 3650) SIG_NAME GND\g
J 0
(-3515 3660);
DISPLAY 0.659574 (-3515 3660);
PAINT MONO (-3515 3660);
DISPLAY INVISIBLE (-3515 3660);
FORCEPROP 1 LAST HDL_POWER GND
J 0
(-3525 3750);
DISPLAY 0.872340 (-3525 3750);
PAINT GREEN (-3525 3750);
DISPLAY INVISIBLE (-3525 3750);
FORCEPROP 1 LAST BODY_TYPE PLUMBING
J 0
(-3570 3557);
DISPLAY 0.340426 (-3570 3557);
PAINT GREEN (-3570 3557);
DISPLAY INVISIBLE (-3570 3557);
FORCEPROP 2 LAST CDS_LIB mstr_symbols
J 0
(-3525 3600);
PAINT ORANGE (-3525 3600);
DISPLAY INVISIBLE (-3525 3600);
FORCEPROP 1 LAST VOLTAGE 0.0V
J 0
(-3570 3557);
DISPLAY 0.340426 (-3570 3557);
PAINT SKYBLUE (-3570 3557);
DISPLAY INVISIBLE (-3570 3557);
FORCEPROP 1 LAST SIZE 1B
J 0
(-3450 3550);
DISPLAY 0.872340 (-3450 3550);
PAINT AQUA (-3450 3550);
DISPLAY INVISIBLE (-3450 3550);
FORCEPROP 1 LAST PATH I46
J 0
(-3450 3600);
DISPLAY 0.872340 (-3450 3600);
PAINT AQUA (-3450 3600);
DISPLAY INVISIBLE (-3450 3600);
FORCEADD OFFPAGE..1
(-4775 4200);
FORCEPROP 2 LAST $XR1 139 
J 0
(-5147 4200);
DISPLAY 0.638298 (-5147 4200);
PAINT MONO (-5147 4200);
FORCEPROP 2 LAST $XR2 ?
J 0
(-5147 4200);
DISPLAY 0.638298 (-5147 4200);
PAINT MONO (-5147 4200);
FORCEPROP 2 LAST $XR0 121 
J 0
(-5027 4200);
DISPLAY 0.638298 (-5027 4200);
PAINT MONO (-5027 4200);
FORCEPROP 2 LAST PATH I47
J 0
(-5025 4250);
DISPLAY 1.021277 (-5025 4250);
PAINT ORANGE (-5025 4250);
DISPLAY INVISIBLE (-5025 4250);
FORCEPROP 2 LAST CDS_LIB mstr_standard
J 0
(-4775 4200);
PAINT ORANGE (-4775 4200);
DISPLAY INVISIBLE (-4775 4200);
FORCEPROP 1 LAST OFFPAGE TRUE
J 0
(-4450 4075);
DISPLAY 0.872340 (-4450 4075);
PAINT GREEN (-4450 4075);
DISPLAY INVISIBLE (-4450 4075);
FORCEPROP 1 LAST COMMENT_BODY TRUE
J 0
(-4650 4100);
DISPLAY 0.872340 (-4650 4100);
PAINT GREEN (-4650 4100);
DISPLAY INVISIBLE (-4650 4100);
FORCEADD OFFPAGE..1
(-4775 4150);
FORCEPROP 2 LAST $XR2 ?
J 0
(-5147 4150);
DISPLAY 0.638298 (-5147 4150);
PAINT MONO (-5147 4150);
FORCEPROP 2 LAST $XR0 121 
J 0
(-5027 4150);
DISPLAY 0.638298 (-5027 4150);
PAINT MONO (-5027 4150);
FORCEPROP 2 LAST $XR1 139 
J 0
(-5147 4150);
DISPLAY 0.638298 (-5147 4150);
PAINT MONO (-5147 4150);
FORCEPROP 2 LAST PATH I48
J 0
(-5025 4200);
DISPLAY 1.021277 (-5025 4200);
PAINT ORANGE (-5025 4200);
DISPLAY INVISIBLE (-5025 4200);
FORCEPROP 2 LAST CDS_LIB mstr_standard
J 0
(-4775 4150);
PAINT ORANGE (-4775 4150);
DISPLAY INVISIBLE (-4775 4150);
FORCEPROP 1 LAST OFFPAGE TRUE
J 0
(-4450 4025);
DISPLAY 0.872340 (-4450 4025);
PAINT GREEN (-4450 4025);
DISPLAY INVISIBLE (-4450 4025);
FORCEPROP 1 LAST COMMENT_BODY TRUE
J 0
(-4650 4050);
DISPLAY 0.872340 (-4650 4050);
PAINT GREEN (-4650 4050);
DISPLAY INVISIBLE (-4650 4050);
FORCEADD OFFPAGE..1
(-4775 4250);
FORCEPROP 2 LAST $XR1 139 
J 0
(-5147 4250);
DISPLAY 0.638298 (-5147 4250);
PAINT MONO (-5147 4250);
FORCEPROP 2 LAST $XR0 121 
J 0
(-5027 4250);
DISPLAY 0.638298 (-5027 4250);
PAINT MONO (-5027 4250);
FORCEPROP 2 LAST PATH I49
J 0
(-5025 4300);
DISPLAY 1.021277 (-5025 4300);
PAINT ORANGE (-5025 4300);
DISPLAY INVISIBLE (-5025 4300);
FORCEPROP 2 LAST CDS_LIB mstr_standard
J 0
(-4775 4250);
PAINT ORANGE (-4775 4250);
DISPLAY INVISIBLE (-4775 4250);
FORCEPROP 1 LAST OFFPAGE TRUE
J 0
(-4450 4125);
DISPLAY 0.872340 (-4450 4125);
PAINT GREEN (-4450 4125);
DISPLAY INVISIBLE (-4450 4125);
FORCEPROP 1 LAST COMMENT_BODY TRUE
J 0
(-4650 4150);
DISPLAY 0.872340 (-4650 4150);
PAINT GREEN (-4650 4150);
DISPLAY INVISIBLE (-4650 4150);
FORCEADD P3V3_STBY..1
(1950 5100);
FORCEPROP 3 LASTPIN (1950 5050) SIG_NAME P3V3_STBY\g
J 0
(1960 5060);
DISPLAY 0.659574 (1960 5060);
PAINT MONO (1960 5060);
DISPLAY INVISIBLE (1960 5060);
FORCEPROP 2 LAST CDS_LIB mstr_symbols
J 0
(1950 5100);
PAINT ORANGE (1950 5100);
DISPLAY INVISIBLE (1950 5100);
FORCEPROP 1 LAST SIZE 1B
J 0
(1995 5122);
DISPLAY 0.340426 (1995 5122);
PAINT GREEN (1995 5122);
DISPLAY INVISIBLE (1995 5122);
FORCEPROP 1 LAST VOLTAGE 3.3V
J 0
(1905 5057);
DISPLAY 0.340426 (1905 5057);
PAINT SKYBLUE (1905 5057);
DISPLAY INVISIBLE (1905 5057);
FORCEPROP 1 LAST PATH I5
J 0
(1995 5102);
DISPLAY 0.340426 (1995 5102);
PAINT GREEN (1995 5102);
DISPLAY INVISIBLE (1995 5102);
FORCEPROP 1 LAST BODY_TYPE PLUMBING
J 0
(1905 5057);
DISPLAY 0.340426 (1905 5057);
PAINT GREEN (1905 5057);
DISPLAY INVISIBLE (1905 5057);
FORCEPROP 1 LAST HDL_POWER P3V3_STBY
J 0
(1650 4975);
DISPLAY 0.872340 (1650 4975);
PAINT ORANGE (1650 4975);
DISPLAY INVISIBLE (1650 4975);
FORCEADD OFFPAGE..1
(-4775 4300);
FORCEPROP 2 LAST $XR0 121 
J 0
(-5027 4300);
DISPLAY 0.638298 (-5027 4300);
PAINT MONO (-5027 4300);
FORCEPROP 2 LAST $XR1 125 
J 0
(-5147 4300);
DISPLAY 0.638298 (-5147 4300);
PAINT MONO (-5147 4300);
FORCEPROP 2 LAST PATH I50
J 0
(-5025 4350);
DISPLAY 1.021277 (-5025 4350);
PAINT ORANGE (-5025 4350);
DISPLAY INVISIBLE (-5025 4350);
FORCEPROP 2 LAST CDS_LIB mstr_standard
J 0
(-4775 4300);
PAINT MONO (-4775 4300);
DISPLAY INVISIBLE (-4775 4300);
FORCEPROP 1 LAST OFFPAGE TRUE
J 0
(-4450 4175);
DISPLAY 0.872340 (-4450 4175);
PAINT GREEN (-4450 4175);
DISPLAY INVISIBLE (-4450 4175);
FORCEPROP 1 LAST COMMENT_BODY TRUE
J 0
(-4650 4200);
DISPLAY 0.872340 (-4650 4200);
PAINT GREEN (-4650 4200);
DISPLAY INVISIBLE (-4650 4200);
FORCEADD OFFPAGE..1
(-4775 3900);
FORCEPROP 2 LAST $XR0 186 
J 0
(-5027 3900);
DISPLAY 0.638298 (-5027 3900);
PAINT MONO (-5027 3900);
FORCEPROP 2 LAST PATH I51
J 0
(-5025 3950);
DISPLAY 1.021277 (-5025 3950);
PAINT ORANGE (-5025 3950);
DISPLAY INVISIBLE (-5025 3950);
FORCEPROP 2 LAST CDS_LIB mstr_standard
J 0
(-4775 3900);
PAINT ORANGE (-4775 3900);
DISPLAY INVISIBLE (-4775 3900);
FORCEPROP 1 LAST OFFPAGE TRUE
J 0
(-4450 3775);
DISPLAY 0.872340 (-4450 3775);
PAINT GREEN (-4450 3775);
DISPLAY INVISIBLE (-4450 3775);
FORCEPROP 1 LAST COMMENT_BODY TRUE
J 0
(-4650 3800);
DISPLAY 0.872340 (-4650 3800);
PAINT GREEN (-4650 3800);
DISPLAY INVISIBLE (-4650 3800);
FORCEADD OFFPAGE..1
(-4775 4000);
FORCEPROP 2 LAST $XR0 152 
J 0
(-5027 4000);
DISPLAY 0.638298 (-5027 4000);
PAINT MONO (-5027 4000);
FORCEPROP 2 LAST PATH I52
J 0
(-5025 4050);
DISPLAY 1.021277 (-5025 4050);
PAINT ORANGE (-5025 4050);
DISPLAY INVISIBLE (-5025 4050);
FORCEPROP 2 LAST BOM_COST SM_CONTROLLER
J 0
(-4325 4050);
PAINT MONO (-4325 4050);
DISPLAY INVISIBLE (-4325 4050);
FORCEPROP 2 LAST ROOM BMC
J 0
(-5025 4075);
DISPLAY 1.361702 (-5025 4075);
PAINT ORANGE (-5025 4075);
DISPLAY INVISIBLE (-5025 4075);
FORCEPROP 2 LAST CDS_LIB mstr_standard
J 0
(-4775 4000);
PAINT ORANGE (-4775 4000);
DISPLAY INVISIBLE (-4775 4000);
FORCEPROP 1 LAST OFFPAGE TRUE
J 0
(-4450 3875);
DISPLAY 0.872340 (-4450 3875);
PAINT GREEN (-4450 3875);
DISPLAY INVISIBLE (-4450 3875);
FORCEPROP 1 LAST COMMENT_BODY TRUE
J 0
(-4650 3900);
DISPLAY 0.872340 (-4650 3900);
PAINT GREEN (-4650 3900);
DISPLAY INVISIBLE (-4650 3900);
FORCEADD OFFPAGE..1
(-4775 4050);
FORCEPROP 2 LAST $XR0 101 
J 0
(-5027 4050);
DISPLAY 0.638298 (-5027 4050);
PAINT MONO (-5027 4050);
FORCEPROP 2 LAST PATH I53
J 0
(-5025 4100);
DISPLAY 1.021277 (-5025 4100);
PAINT ORANGE (-5025 4100);
DISPLAY INVISIBLE (-5025 4100);
FORCEPROP 2 LAST CDS_LIB mstr_standard
J 0
(-4775 4050);
PAINT ORANGE (-4775 4050);
DISPLAY INVISIBLE (-4775 4050);
FORCEPROP 1 LAST OFFPAGE TRUE
J 0
(-4450 3925);
DISPLAY 0.872340 (-4450 3925);
PAINT GREEN (-4450 3925);
DISPLAY INVISIBLE (-4450 3925);
FORCEPROP 1 LAST COMMENT_BODY TRUE
J 0
(-4650 3950);
DISPLAY 0.872340 (-4650 3950);
PAINT GREEN (-4650 3950);
DISPLAY INVISIBLE (-4650 3950);
FORCEADD OFFPAGE..1
(-4775 3850);
FORCEPROP 2 LAST $XR0 186 
J 0
(-5027 3850);
DISPLAY 0.638298 (-5027 3850);
PAINT MONO (-5027 3850);
FORCEPROP 2 LAST PATH I54
J 0
(-5025 3900);
DISPLAY 1.021277 (-5025 3900);
PAINT ORANGE (-5025 3900);
DISPLAY INVISIBLE (-5025 3900);
FORCEPROP 2 LAST CDS_LIB mstr_standard
J 0
(-4775 3850);
PAINT ORANGE (-4775 3850);
DISPLAY INVISIBLE (-4775 3850);
FORCEPROP 1 LAST OFFPAGE TRUE
J 0
(-4450 3725);
DISPLAY 0.872340 (-4450 3725);
PAINT GREEN (-4450 3725);
DISPLAY INVISIBLE (-4450 3725);
FORCEPROP 1 LAST COMMENT_BODY TRUE
J 0
(-4650 3750);
DISPLAY 0.872340 (-4650 3750);
PAINT GREEN (-4650 3750);
DISPLAY INVISIBLE (-4650 3750);
FORCEADD OFFPAGE..1
(-4775 3750);
FORCEPROP 2 LAST $XR0 186 
J 0
(-5027 3750);
DISPLAY 0.638298 (-5027 3750);
PAINT MONO (-5027 3750);
FORCEPROP 2 LAST PATH I55
J 0
(-5025 3800);
DISPLAY 1.021277 (-5025 3800);
PAINT ORANGE (-5025 3800);
DISPLAY INVISIBLE (-5025 3800);
FORCEPROP 2 LAST CDS_LIB mstr_standard
J 0
(-4775 3750);
PAINT ORANGE (-4775 3750);
DISPLAY INVISIBLE (-4775 3750);
FORCEPROP 1 LAST OFFPAGE TRUE
J 0
(-4450 3625);
DISPLAY 0.872340 (-4450 3625);
PAINT GREEN (-4450 3625);
DISPLAY INVISIBLE (-4450 3625);
FORCEPROP 1 LAST COMMENT_BODY TRUE
J 0
(-4650 3650);
DISPLAY 0.872340 (-4650 3650);
PAINT GREEN (-4650 3650);
DISPLAY INVISIBLE (-4650 3650);
FORCEADD OFFPAGE..1
(-4775 3800);
FORCEPROP 2 LAST $XR0 186 
J 0
(-5027 3800);
DISPLAY 0.638298 (-5027 3800);
PAINT MONO (-5027 3800);
FORCEPROP 2 LAST PATH I56
J 0
(-5025 3850);
DISPLAY 1.021277 (-5025 3850);
PAINT ORANGE (-5025 3850);
DISPLAY INVISIBLE (-5025 3850);
FORCEPROP 2 LAST CDS_LIB mstr_standard
J 0
(-4775 3800);
PAINT ORANGE (-4775 3800);
DISPLAY INVISIBLE (-4775 3800);
FORCEPROP 1 LAST OFFPAGE TRUE
J 0
(-4450 3675);
DISPLAY 0.872340 (-4450 3675);
PAINT GREEN (-4450 3675);
DISPLAY INVISIBLE (-4450 3675);
FORCEPROP 1 LAST COMMENT_BODY TRUE
J 0
(-4650 3700);
DISPLAY 0.872340 (-4650 3700);
PAINT GREEN (-4650 3700);
DISPLAY INVISIBLE (-4650 3700);
FORCEADD OFFPAGE..1
(-4650 2350);
FORCEPROP 2 LAST $XR2 120 
J 0
(-5142 2350);
DISPLAY 0.638298 (-5142 2350);
PAINT MONO (-5142 2350);
FORCEPROP 2 LAST $XR1 181 
J 0
(-5022 2350);
DISPLAY 0.638298 (-5022 2350);
PAINT MONO (-5022 2350);
FORCEPROP 2 LAST $XR0 161 
J 0
(-4902 2350);
DISPLAY 0.638298 (-4902 2350);
PAINT MONO (-4902 2350);
FORCEPROP 1 LAST COMMENT_BODY TRUE
J 0
(-4525 2250);
DISPLAY 0.872340 (-4525 2250);
PAINT GREEN (-4525 2250);
DISPLAY INVISIBLE (-4525 2250);
FORCEPROP 1 LAST OFFPAGE TRUE
J 0
(-4325 2225);
DISPLAY 0.872340 (-4325 2225);
PAINT GREEN (-4325 2225);
DISPLAY INVISIBLE (-4325 2225);
FORCEPROP 2 LAST PATH I57
J 0
(-4900 2400);
DISPLAY 1.021277 (-4900 2400);
PAINT ORANGE (-4900 2400);
DISPLAY INVISIBLE (-4900 2400);
FORCEPROP 2 LAST CDS_LIB mstr_standard
J 0
(-4650 2350);
PAINT ORANGE (-4650 2350);
DISPLAY INVISIBLE (-4650 2350);
FORCEADD OFFPAGE..1
(-4650 2400);
FORCEPROP 2 LAST $XR2 120 
J 0
(-5142 2400);
DISPLAY 0.638298 (-5142 2400);
PAINT MONO (-5142 2400);
FORCEPROP 2 LAST $XR1 181 
J 0
(-5022 2400);
DISPLAY 0.638298 (-5022 2400);
PAINT MONO (-5022 2400);
FORCEPROP 2 LAST $XR0 161 
J 0
(-4902 2400);
DISPLAY 0.638298 (-4902 2400);
PAINT MONO (-4902 2400);
FORCEPROP 1 LAST COMMENT_BODY TRUE
J 0
(-4525 2300);
DISPLAY 0.872340 (-4525 2300);
PAINT GREEN (-4525 2300);
DISPLAY INVISIBLE (-4525 2300);
FORCEPROP 1 LAST OFFPAGE TRUE
J 0
(-4325 2275);
DISPLAY 0.872340 (-4325 2275);
PAINT GREEN (-4325 2275);
DISPLAY INVISIBLE (-4325 2275);
FORCEPROP 2 LAST CDS_LIB mstr_standard
J 0
(-4650 2400);
PAINT ORANGE (-4650 2400);
DISPLAY INVISIBLE (-4650 2400);
FORCEPROP 2 LAST PATH I58
J 0
(-4900 2450);
DISPLAY 1.021277 (-4900 2450);
PAINT ORANGE (-4900 2450);
DISPLAY INVISIBLE (-4900 2450);
FORCEADD OFFPAGE..1
(-4650 2450);
FORCEPROP 2 LAST $XR2 120 
J 0
(-5142 2450);
DISPLAY 0.638298 (-5142 2450);
PAINT MONO (-5142 2450);
FORCEPROP 2 LAST $XR1 181 
J 0
(-5022 2450);
DISPLAY 0.638298 (-5022 2450);
PAINT MONO (-5022 2450);
FORCEPROP 2 LAST $XR0 161 
J 0
(-4902 2450);
DISPLAY 0.638298 (-4902 2450);
PAINT MONO (-4902 2450);
FORCEPROP 1 LAST COMMENT_BODY TRUE
J 0
(-4525 2350);
DISPLAY 0.872340 (-4525 2350);
PAINT GREEN (-4525 2350);
DISPLAY INVISIBLE (-4525 2350);
FORCEPROP 1 LAST OFFPAGE TRUE
J 0
(-4325 2325);
DISPLAY 0.872340 (-4325 2325);
PAINT GREEN (-4325 2325);
DISPLAY INVISIBLE (-4325 2325);
FORCEPROP 2 LAST CDS_LIB mstr_standard
J 0
(-4650 2450);
PAINT ORANGE (-4650 2450);
DISPLAY INVISIBLE (-4650 2450);
FORCEPROP 2 LAST PATH I59
J 0
(-4900 2500);
DISPLAY 1.021277 (-4900 2500);
PAINT ORANGE (-4900 2500);
DISPLAY INVISIBLE (-4900 2500);
FORCEADD OFFPAGE..2
(1400 4875);
FORCEPROP 2 LAST $XR0 147 
J 0
(1589 4875);
DISPLAY 0.638298 (1589 4875);
PAINT MONO (1589 4875);
FORCEPROP 2 LAST $XR1 151 
J 0
(1709 4875);
DISPLAY 0.638298 (1709 4875);
PAINT MONO (1709 4875);
FORCEPROP 2 LAST PATH I6
J 0
(1725 4925);
DISPLAY 1.021277 (1725 4925);
PAINT ORANGE (1725 4925);
DISPLAY INVISIBLE (1725 4925);
FORCEPROP 2 LAST CDS_LIB mstr_standard
J 0
(1400 4875);
PAINT MONO (1400 4875);
DISPLAY INVISIBLE (1400 4875);
FORCEPROP 1 LAST OFFPAGE TRUE
J 0
(1725 4750);
DISPLAY 0.872340 (1725 4750);
PAINT GREEN (1725 4750);
DISPLAY INVISIBLE (1725 4750);
FORCEPROP 1 LAST COMMENT_BODY TRUE
J 0
(1355 4780);
DISPLAY 0.872340 (1355 4780);
PAINT GREEN (1355 4780);
DISPLAY INVISIBLE (1355 4780);
FORCEADD OFFPAGE..1
(-4650 2500);
FORCEPROP 2 LAST $XR2 120 
J 0
(-5142 2500);
DISPLAY 0.638298 (-5142 2500);
PAINT MONO (-5142 2500);
FORCEPROP 2 LAST $XR1 181 
J 0
(-5022 2500);
DISPLAY 0.638298 (-5022 2500);
PAINT MONO (-5022 2500);
FORCEPROP 2 LAST $XR0 161 
J 0
(-4902 2500);
DISPLAY 0.638298 (-4902 2500);
PAINT MONO (-4902 2500);
FORCEPROP 1 LAST COMMENT_BODY TRUE
J 0
(-4525 2400);
DISPLAY 0.872340 (-4525 2400);
PAINT GREEN (-4525 2400);
DISPLAY INVISIBLE (-4525 2400);
FORCEPROP 1 LAST OFFPAGE TRUE
J 0
(-4325 2375);
DISPLAY 0.872340 (-4325 2375);
PAINT GREEN (-4325 2375);
DISPLAY INVISIBLE (-4325 2375);
FORCEPROP 2 LAST CDS_LIB mstr_standard
J 0
(-4650 2500);
PAINT ORANGE (-4650 2500);
DISPLAY INVISIBLE (-4650 2500);
FORCEPROP 2 LAST PATH I60
J 0
(-4900 2550);
DISPLAY 1.021277 (-4900 2550);
PAINT ORANGE (-4900 2550);
DISPLAY INVISIBLE (-4900 2550);
FORCEADD RES..2
(-3525 1950);
FORCEPROP 1 LAST PART_NUMBER G21796-010
J 0
(-3485 1825);
DISPLAY 0.617021 (-3485 1825);
PAINT BLUE (-3485 1825);
FORCEPROP 1 LAST WATTAGE 1/16W
J 0
(-3485 1925);
DISPLAY 0.617021 (-3485 1925);
PAINT SKYBLUE (-3485 1925);
FORCEPROP 1 LAST TOLERANCE 1%
J 0
(-3480 1975);
DISPLAY 0.617021 (-3480 1975);
PAINT SKYBLUE (-3480 1975);
FORCEPROP 1 LASTPIN (-3525 2050) $PN 1
J 0
(-3520 2012);
DISPLAY 0.617021 (-3520 2012);
PAINT ORANGE (-3520 2012);
FORCEPROP 1 LASTPIN (-3525 1850) $PN 2
J 0
(-3520 1860);
DISPLAY 0.617021 (-3520 1860);
PAINT ORANGE (-3520 1860);
FORCEPROP 1 LAST VALUE 100.0K
J 0
(-3480 2025);
DISPLAY 0.617021 (-3480 2025);
PAINT SKYBLUE (-3480 2025);
FORCEPROP 1 LAST LOCATION R1U1
J 0
(-3480 2075);
DISPLAY 0.617021 (-3480 2075);
PAINT AQUA (-3480 2075);
FORCEPROP 1 LAST MATERIAL CHIP
J 0
(-3485 1875);
DISPLAY 0.617021 (-3485 1875);
PAINT SKYBLUE (-3485 1875);
FORCEPROP 1 LAST PACK_TYPE 0402
J 0
(-3485 1775);
DISPLAY 0.617021 (-3485 1775);
PAINT SKYBLUE (-3485 1775);
FORCEPROP 1 LAST PATH I61
J 0
(-3475 2125);
DISPLAY 0.978723 (-3475 2125);
PAINT WHITE (-3475 2125);
DISPLAY INVISIBLE (-3475 2125);
FORCEPROP 2 LAST SEC_TYPE 0402
J 0
(-3475 2175);
DISPLAY 1.021277 (-3475 2175);
PAINT ORANGE (-3475 2175);
DISPLAY INVISIBLE (-3475 2175);
FORCEPROP 2 LAST SEC 1
J 0
(-3475 2175);
DISPLAY 0.680851 (-3475 2175);
PAINT MONO (-3475 2175);
DISPLAY INVISIBLE (-3475 2175);
FORCEPROP 2 LAST CDS_LOCATION R1U1
J 0
(-3480 2075);
DISPLAY 0.617021 (-3480 2075);
PAINT AQUA (-3480 2075);
DISPLAY INVISIBLE (-3480 2075);
FORCEPROP 2 LAST CDS_LIB mstr_discrete
J 0
(-3525 1950);
PAINT ORANGE (-3525 1950);
DISPLAY INVISIBLE (-3525 1950);
FORCEADD RES..2
(-3775 1950);
FORCEPROP 1 LASTPIN (-3775 2050) $PN 1
J 0
(-3770 2012);
DISPLAY 0.617021 (-3770 2012);
PAINT ORANGE (-3770 2012);
FORCEPROP 1 LASTPIN (-3775 1850) $PN 2
J 0
(-3770 1860);
DISPLAY 0.617021 (-3770 1860);
PAINT ORANGE (-3770 1860);
FORCEPROP 1 LAST LOCATION R1U2
J 0
(-3730 2075);
DISPLAY 0.617021 (-3730 2075);
PAINT AQUA (-3730 2075);
FORCEPROP 1 LAST VALUE 100.0K
J 0
(-3730 2025);
DISPLAY 0.617021 (-3730 2025);
PAINT SKYBLUE (-3730 2025);
FORCEPROP 1 LAST TOLERANCE 1%
J 0
(-3730 1975);
DISPLAY 0.617021 (-3730 1975);
PAINT SKYBLUE (-3730 1975);
FORCEPROP 1 LAST WATTAGE 1/16W
J 0
(-3735 1925);
DISPLAY 0.617021 (-3735 1925);
PAINT SKYBLUE (-3735 1925);
FORCEPROP 1 LAST MATERIAL CHIP
J 0
(-3735 1875);
DISPLAY 0.617021 (-3735 1875);
PAINT SKYBLUE (-3735 1875);
FORCEPROP 1 LAST PART_NUMBER G21796-010
J 0
(-3735 1825);
DISPLAY 0.617021 (-3735 1825);
PAINT BLUE (-3735 1825);
FORCEPROP 1 LAST PACK_TYPE 0402
J 0
(-3735 1775);
DISPLAY 0.617021 (-3735 1775);
PAINT SKYBLUE (-3735 1775);
FORCEPROP 1 LAST PATH I62
J 0
(-3725 2125);
DISPLAY 0.978723 (-3725 2125);
PAINT WHITE (-3725 2125);
DISPLAY INVISIBLE (-3725 2125);
FORCEPROP 2 LAST SEC 1
J 0
(-3725 2175);
DISPLAY 0.680851 (-3725 2175);
PAINT MONO (-3725 2175);
DISPLAY INVISIBLE (-3725 2175);
FORCEPROP 2 LAST SEC_TYPE 0402
J 0
(-3725 2175);
DISPLAY 1.021277 (-3725 2175);
PAINT ORANGE (-3725 2175);
DISPLAY INVISIBLE (-3725 2175);
FORCEPROP 2 LAST CDS_LOCATION R1U2
J 0
(-3730 2075);
DISPLAY 0.617021 (-3730 2075);
PAINT AQUA (-3730 2075);
DISPLAY INVISIBLE (-3730 2075);
FORCEPROP 2 LAST CDS_LIB mstr_discrete
J 0
(-3775 1950);
PAINT ORANGE (-3775 1950);
DISPLAY INVISIBLE (-3775 1950);
FORCEADD GND..1
(-3525 1725);
FORCEPROP 3 LASTPIN (-3525 1775) SIG_NAME GND\g
J 0
(-3515 1785);
DISPLAY 0.659574 (-3515 1785);
PAINT MONO (-3515 1785);
DISPLAY INVISIBLE (-3515 1785);
FORCEPROP 1 LAST PATH I63
J 0
(-3450 1725);
DISPLAY 0.872340 (-3450 1725);
PAINT AQUA (-3450 1725);
DISPLAY INVISIBLE (-3450 1725);
FORCEPROP 1 LAST SIZE 1B
J 0
(-3450 1675);
DISPLAY 0.872340 (-3450 1675);
PAINT AQUA (-3450 1675);
DISPLAY INVISIBLE (-3450 1675);
FORCEPROP 1 LAST VOLTAGE 0.0V
J 0
(-3570 1682);
DISPLAY 0.340426 (-3570 1682);
PAINT SKYBLUE (-3570 1682);
DISPLAY INVISIBLE (-3570 1682);
FORCEPROP 2 LAST CDS_LIB mstr_symbols
J 0
(-3525 1725);
PAINT ORANGE (-3525 1725);
DISPLAY INVISIBLE (-3525 1725);
FORCEPROP 1 LAST BODY_TYPE PLUMBING
J 0
(-3570 1682);
DISPLAY 0.340426 (-3570 1682);
PAINT GREEN (-3570 1682);
DISPLAY INVISIBLE (-3570 1682);
FORCEPROP 1 LAST HDL_POWER GND
J 0
(-3525 1875);
DISPLAY 0.872340 (-3525 1875);
PAINT GREEN (-3525 1875);
DISPLAY INVISIBLE (-3525 1875);
FORCEADD GND..1
(-3775 1725);
FORCEPROP 3 LASTPIN (-3775 1775) SIG_NAME GND\g
J 0
(-3765 1785);
DISPLAY 0.659574 (-3765 1785);
PAINT MONO (-3765 1785);
DISPLAY INVISIBLE (-3765 1785);
FORCEPROP 1 LAST PATH I64
J 0
(-3700 1725);
DISPLAY 0.872340 (-3700 1725);
PAINT AQUA (-3700 1725);
DISPLAY INVISIBLE (-3700 1725);
FORCEPROP 1 LAST SIZE 1B
J 0
(-3700 1675);
DISPLAY 0.872340 (-3700 1675);
PAINT AQUA (-3700 1675);
DISPLAY INVISIBLE (-3700 1675);
FORCEPROP 2 LAST CDS_LIB mstr_symbols
J 0
(-3775 1725);
PAINT ORANGE (-3775 1725);
DISPLAY INVISIBLE (-3775 1725);
FORCEPROP 1 LAST VOLTAGE 0.0V
J 0
(-3820 1682);
DISPLAY 0.340426 (-3820 1682);
PAINT SKYBLUE (-3820 1682);
DISPLAY INVISIBLE (-3820 1682);
FORCEPROP 1 LAST BODY_TYPE PLUMBING
J 0
(-3820 1682);
DISPLAY 0.340426 (-3820 1682);
PAINT GREEN (-3820 1682);
DISPLAY INVISIBLE (-3820 1682);
FORCEPROP 1 LAST HDL_POWER GND
J 0
(-3775 1875);
DISPLAY 0.872340 (-3775 1875);
PAINT GREEN (-3775 1875);
DISPLAY INVISIBLE (-3775 1875);
FORCEADD RES..2
(-4025 1950);
FORCEPROP 1 LAST LOCATION R1U4
J 0
(-3980 2075);
DISPLAY 0.617021 (-3980 2075);
PAINT AQUA (-3980 2075);
FORCEPROP 1 LAST PART_NUMBER G21796-010
J 0
(-3985 1825);
DISPLAY 0.617021 (-3985 1825);
PAINT BLUE (-3985 1825);
FORCEPROP 1 LAST TOLERANCE 1%
J 0
(-3980 1975);
DISPLAY 0.617021 (-3980 1975);
PAINT SKYBLUE (-3980 1975);
FORCEPROP 1 LASTPIN (-4025 2050) $PN 1
J 0
(-4020 2012);
DISPLAY 0.617021 (-4020 2012);
PAINT ORANGE (-4020 2012);
FORCEPROP 1 LAST WATTAGE 1/16W
J 0
(-3985 1925);
DISPLAY 0.617021 (-3985 1925);
PAINT SKYBLUE (-3985 1925);
FORCEPROP 1 LAST PACK_TYPE 0402
J 0
(-3985 1775);
DISPLAY 0.617021 (-3985 1775);
PAINT SKYBLUE (-3985 1775);
FORCEPROP 1 LAST VALUE 100.0K
J 0
(-3980 2025);
DISPLAY 0.617021 (-3980 2025);
PAINT SKYBLUE (-3980 2025);
FORCEPROP 1 LASTPIN (-4025 1850) $PN 2
J 0
(-4020 1860);
DISPLAY 0.617021 (-4020 1860);
PAINT ORANGE (-4020 1860);
FORCEPROP 1 LAST MATERIAL CHIP
J 0
(-3985 1875);
DISPLAY 0.617021 (-3985 1875);
PAINT SKYBLUE (-3985 1875);
FORCEPROP 1 LAST PATH I65
J 0
(-3975 2125);
DISPLAY 0.978723 (-3975 2125);
PAINT WHITE (-3975 2125);
DISPLAY INVISIBLE (-3975 2125);
FORCEPROP 2 LAST CDS_LIB mstr_discrete
J 0
(-4025 1950);
PAINT ORANGE (-4025 1950);
DISPLAY INVISIBLE (-4025 1950);
FORCEPROP 2 LAST CDS_LOCATION R1U4
J 0
(-3980 2075);
DISPLAY 0.617021 (-3980 2075);
PAINT AQUA (-3980 2075);
DISPLAY INVISIBLE (-3980 2075);
FORCEPROP 2 LAST SEC 1
J 0
(-3975 2175);
DISPLAY 0.680851 (-3975 2175);
PAINT MONO (-3975 2175);
DISPLAY INVISIBLE (-3975 2175);
FORCEPROP 2 LAST SEC_TYPE 0402
J 0
(-3975 2175);
DISPLAY 1.021277 (-3975 2175);
PAINT ORANGE (-3975 2175);
DISPLAY INVISIBLE (-3975 2175);
FORCEADD RES..2
(-4275 1950);
FORCEPROP 1 LAST VALUE 100.0K
J 0
(-4230 2025);
DISPLAY 0.617021 (-4230 2025);
PAINT SKYBLUE (-4230 2025);
FORCEPROP 1 LAST TOLERANCE 1%
J 0
(-4230 1975);
DISPLAY 0.617021 (-4230 1975);
PAINT SKYBLUE (-4230 1975);
FORCEPROP 1 LAST WATTAGE 1/16W
J 0
(-4235 1925);
DISPLAY 0.617021 (-4235 1925);
PAINT SKYBLUE (-4235 1925);
FORCEPROP 1 LAST PART_NUMBER G21796-010
J 0
(-4235 1825);
DISPLAY 0.617021 (-4235 1825);
PAINT BLUE (-4235 1825);
FORCEPROP 1 LAST MATERIAL CHIP
J 0
(-4235 1875);
DISPLAY 0.617021 (-4235 1875);
PAINT SKYBLUE (-4235 1875);
FORCEPROP 1 LAST LOCATION R1U5
J 0
(-4230 2075);
DISPLAY 0.617021 (-4230 2075);
PAINT AQUA (-4230 2075);
FORCEPROP 1 LASTPIN (-4275 1850) $PN 2
J 0
(-4270 1860);
DISPLAY 0.617021 (-4270 1860);
PAINT ORANGE (-4270 1860);
FORCEPROP 1 LASTPIN (-4275 2050) $PN 1
J 0
(-4270 2012);
DISPLAY 0.617021 (-4270 2012);
PAINT ORANGE (-4270 2012);
FORCEPROP 1 LAST PACK_TYPE 0402
J 0
(-4235 1775);
DISPLAY 0.617021 (-4235 1775);
PAINT SKYBLUE (-4235 1775);
FORCEPROP 1 LAST PATH I66
J 0
(-4225 2125);
DISPLAY 0.978723 (-4225 2125);
PAINT WHITE (-4225 2125);
DISPLAY INVISIBLE (-4225 2125);
FORCEPROP 2 LAST CDS_LIB mstr_discrete
J 0
(-4275 1950);
PAINT ORANGE (-4275 1950);
DISPLAY INVISIBLE (-4275 1950);
FORCEPROP 2 LAST CDS_LOCATION R1U5
J 0
(-4230 2075);
DISPLAY 0.617021 (-4230 2075);
PAINT AQUA (-4230 2075);
DISPLAY INVISIBLE (-4230 2075);
FORCEPROP 2 LAST SEC_TYPE 0402
J 0
(-4225 2175);
DISPLAY 1.021277 (-4225 2175);
PAINT ORANGE (-4225 2175);
DISPLAY INVISIBLE (-4225 2175);
FORCEPROP 2 LAST SEC 1
J 0
(-4225 2175);
DISPLAY 0.680851 (-4225 2175);
PAINT MONO (-4225 2175);
DISPLAY INVISIBLE (-4225 2175);
FORCEADD GND..1
(-4025 1725);
FORCEPROP 3 LASTPIN (-4025 1775) SIG_NAME GND\g
J 0
(-4015 1785);
DISPLAY 0.659574 (-4015 1785);
PAINT MONO (-4015 1785);
DISPLAY INVISIBLE (-4015 1785);
FORCEPROP 1 LAST PATH I67
J 0
(-3950 1725);
DISPLAY 0.872340 (-3950 1725);
PAINT AQUA (-3950 1725);
DISPLAY INVISIBLE (-3950 1725);
FORCEPROP 2 LAST CDS_LIB mstr_symbols
J 0
(-4025 1725);
PAINT ORANGE (-4025 1725);
DISPLAY INVISIBLE (-4025 1725);
FORCEPROP 1 LAST VOLTAGE 0.0V
J 0
(-4070 1682);
DISPLAY 0.340426 (-4070 1682);
PAINT SKYBLUE (-4070 1682);
DISPLAY INVISIBLE (-4070 1682);
FORCEPROP 1 LAST SIZE 1B
J 0
(-3950 1675);
DISPLAY 0.872340 (-3950 1675);
PAINT AQUA (-3950 1675);
DISPLAY INVISIBLE (-3950 1675);
FORCEPROP 1 LAST BODY_TYPE PLUMBING
J 0
(-4070 1682);
DISPLAY 0.340426 (-4070 1682);
PAINT GREEN (-4070 1682);
DISPLAY INVISIBLE (-4070 1682);
FORCEPROP 1 LAST HDL_POWER GND
J 0
(-4025 1875);
DISPLAY 0.872340 (-4025 1875);
PAINT GREEN (-4025 1875);
DISPLAY INVISIBLE (-4025 1875);
FORCEADD GND..1
(-4275 1725);
FORCEPROP 3 LASTPIN (-4275 1775) SIG_NAME GND\g
J 0
(-4265 1785);
DISPLAY 0.659574 (-4265 1785);
PAINT MONO (-4265 1785);
DISPLAY INVISIBLE (-4265 1785);
FORCEPROP 1 LAST PATH I68
J 0
(-4200 1725);
DISPLAY 0.872340 (-4200 1725);
PAINT AQUA (-4200 1725);
DISPLAY INVISIBLE (-4200 1725);
FORCEPROP 1 LAST VOLTAGE 0.0V
J 0
(-4320 1682);
DISPLAY 0.340426 (-4320 1682);
PAINT SKYBLUE (-4320 1682);
DISPLAY INVISIBLE (-4320 1682);
FORCEPROP 2 LAST CDS_LIB mstr_symbols
J 0
(-4275 1725);
PAINT ORANGE (-4275 1725);
DISPLAY INVISIBLE (-4275 1725);
FORCEPROP 1 LAST SIZE 1B
J 0
(-4200 1675);
DISPLAY 0.872340 (-4200 1675);
PAINT AQUA (-4200 1675);
DISPLAY INVISIBLE (-4200 1675);
FORCEPROP 1 LAST BODY_TYPE PLUMBING
J 0
(-4320 1682);
DISPLAY 0.340426 (-4320 1682);
PAINT GREEN (-4320 1682);
DISPLAY INVISIBLE (-4320 1682);
FORCEPROP 1 LAST HDL_POWER GND
J 0
(-4275 1875);
DISPLAY 0.872340 (-4275 1875);
PAINT GREEN (-4275 1875);
DISPLAY INVISIBLE (-4275 1875);
FORCEADD OFFPAGE..2
(1400 4750);
FORCEPROP 2 LAST $XR0 147 
J 0
(1589 4750);
DISPLAY 0.638298 (1589 4750);
PAINT MONO (1589 4750);
FORCEPROP 2 LAST $XR1 151 
J 0
(1709 4750);
DISPLAY 0.638298 (1709 4750);
PAINT MONO (1709 4750);
FORCEPROP 2 LAST PATH I7
J 0
(1725 4800);
DISPLAY 1.021277 (1725 4800);
PAINT ORANGE (1725 4800);
DISPLAY INVISIBLE (1725 4800);
FORCEPROP 2 LAST CDS_LIB mstr_standard
J 0
(1400 4750);
PAINT MONO (1400 4750);
DISPLAY INVISIBLE (1400 4750);
FORCEPROP 1 LAST OFFPAGE TRUE
J 0
(1725 4625);
DISPLAY 0.872340 (1725 4625);
PAINT GREEN (1725 4625);
DISPLAY INVISIBLE (1725 4625);
FORCEPROP 1 LAST COMMENT_BODY TRUE
J 0
(1355 4655);
DISPLAY 0.872340 (1355 4655);
PAINT GREEN (1355 4655);
DISPLAY INVISIBLE (1355 4655);
FORCEADD OFFPAGE..2
(425 4600);
FORCEPROP 2 LAST $XR1 191 
J 0
(824 4600);
DISPLAY 0.638298 (824 4600);
PAINT MONO (824 4600);
FORCEPROP 2 LAST $XR0 120 
J 0
(704 4600);
DISPLAY 0.638298 (704 4600);
PAINT MONO (704 4600);
FORCEPROP 2 LAST PATH I72
J 0
(600 4675);
DISPLAY 1.021277 (600 4675);
PAINT ORANGE (600 4675);
DISPLAY INVISIBLE (600 4675);
FORCEPROP 2 LAST CDS_LIB mstr_standard
J 0
(425 4600);
PAINT MONO (425 4600);
DISPLAY INVISIBLE (425 4600);
FORCEPROP 1 LAST OFFPAGE TRUE
J 0
(750 4475);
DISPLAY 0.872340 (750 4475);
PAINT GREEN (750 4475);
DISPLAY INVISIBLE (750 4475);
FORCEPROP 1 LAST COMMENT_BODY TRUE
J 0
(380 4505);
DISPLAY 0.872340 (380 4505);
PAINT GREEN (380 4505);
DISPLAY INVISIBLE (380 4505);
FORCEADD OFFPAGE..2
(425 4650);
FORCEPROP 2 LAST $XR2 191 
J 0
(944 4650);
DISPLAY 0.638298 (944 4650);
PAINT MONO (944 4650);
FORCEPROP 2 LAST $XR1 125 
J 0
(824 4650);
DISPLAY 0.638298 (824 4650);
PAINT MONO (824 4650);
FORCEPROP 2 LAST $XR0 119 
J 0
(704 4650);
DISPLAY 0.638298 (704 4650);
PAINT MONO (704 4650);
FORCEPROP 2 LAST PATH I73
J 0
(600 4725);
DISPLAY 1.021277 (600 4725);
PAINT ORANGE (600 4725);
DISPLAY INVISIBLE (600 4725);
FORCEPROP 2 LAST CDS_LIB mstr_standard
J 0
(425 4650);
PAINT MONO (425 4650);
DISPLAY INVISIBLE (425 4650);
FORCEPROP 1 LAST OFFPAGE TRUE
J 0
(750 4525);
DISPLAY 0.872340 (750 4525);
PAINT GREEN (750 4525);
DISPLAY INVISIBLE (750 4525);
FORCEPROP 1 LAST COMMENT_BODY TRUE
J 0
(380 4555);
DISPLAY 0.872340 (380 4555);
PAINT GREEN (380 4555);
DISPLAY INVISIBLE (380 4555);
FORCEADD RES..2
(-100 1825);
FORCEPROP 1 LAST PACK_TYPE 0402
J 0
(-60 1650);
DISPLAY 0.617021 (-60 1650);
PAINT SKYBLUE (-60 1650);
FORCEPROP 1 LAST PART_NUMBER G21796-016
J 0
(-60 1700);
DISPLAY 0.617021 (-60 1700);
PAINT BLUE (-60 1700);
FORCEPROP 1 LAST MATERIAL CHIP
J 0
(-60 1750);
DISPLAY 0.617021 (-60 1750);
PAINT SKYBLUE (-60 1750);
FORCEPROP 1 LAST WATTAGE 1/16W
J 0
(-60 1800);
DISPLAY 0.617021 (-60 1800);
PAINT SKYBLUE (-60 1800);
FORCEPROP 1 LAST TOLERANCE 1%
J 0
(-55 1850);
DISPLAY 0.617021 (-55 1850);
PAINT SKYBLUE (-55 1850);
FORCEPROP 1 LAST VALUE 10.0K
J 0
(-55 1900);
DISPLAY 0.617021 (-55 1900);
PAINT SKYBLUE (-55 1900);
FORCEPROP 1 LAST LOCATION R2N13
J 0
(-55 1950);
DISPLAY 0.617021 (-55 1950);
PAINT AQUA (-55 1950);
FORCEPROP 0 LAST BOM_COST SM_CONTROLLER
J 0
(-50 2150);
DISPLAY 1.021277 (-50 2150);
PAINT ORANGE (-50 2150);
DISPLAY INVISIBLE (-50 2150);
FORCEPROP 0 LAST ROOM BMC
J 0
(-50 2050);
DISPLAY 1.021277 (-50 2050);
PAINT ORANGE (-50 2050);
DISPLAY INVISIBLE (-50 2050);
FORCEPROP 2 LAST CDS_LIB mstr_discrete
J 0
(-100 1825);
PAINT MONO (-100 1825);
DISPLAY INVISIBLE (-100 1825);
FORCEPROP 1 LAST PATH I75
J 0
(-50 2000);
DISPLAY 0.978723 (-50 2000);
PAINT WHITE (-50 2000);
DISPLAY INVISIBLE (-50 2000);
FORCEPROP 1 LASTPIN (-100 1725) $PN 2
J 0
(-95 1735);
DISPLAY 0.787234 (-95 1735);
PAINT ORANGE (-95 1735);
DISPLAY INVISIBLE (-95 1735);
FORCEPROP 1 LASTPIN (-100 1925) $PN 1
J 0
(-95 1887);
DISPLAY 0.787234 (-95 1887);
PAINT ORANGE (-95 1887);
DISPLAY INVISIBLE (-95 1887);
FORCEADD GND..1
(-100 1575);
FORCEPROP 3 LASTPIN (-100 1625) SIG_NAME GND\g
J 0
(-90 1635);
DISPLAY 0.659574 (-90 1635);
PAINT MONO (-90 1635);
DISPLAY INVISIBLE (-90 1635);
FORCEPROP 2 LAST CDS_LIB mstr_symbols
J 0
(-100 1575);
PAINT MONO (-100 1575);
DISPLAY INVISIBLE (-100 1575);
FORCEPROP 1 LAST SIZE 1B
J 0
(-25 1525);
DISPLAY 0.872340 (-25 1525);
PAINT AQUA (-25 1525);
DISPLAY INVISIBLE (-25 1525);
FORCEPROP 1 LAST VOLTAGE 0.0V
J 0
(-145 1532);
DISPLAY 0.340426 (-145 1532);
PAINT GREEN (-145 1532);
DISPLAY INVISIBLE (-145 1532);
FORCEPROP 1 LAST PATH I76
J 0
(-25 1575);
DISPLAY 0.872340 (-25 1575);
PAINT AQUA (-25 1575);
DISPLAY INVISIBLE (-25 1575);
FORCEPROP 1 LAST BODY_TYPE PLUMBING
J 0
(-145 1532);
DISPLAY 0.340426 (-145 1532);
PAINT GREEN (-145 1532);
DISPLAY INVISIBLE (-145 1532);
FORCEPROP 1 LAST HDL_POWER GND
J 0
(-100 1725);
DISPLAY 0.872340 (-100 1725);
PAINT GREEN (-100 1725);
DISPLAY INVISIBLE (-100 1725);
FORCEADD OFFPAGE..2
(1075 2500);
FORCEPROP 2 LAST $XR0 119 
J 0
(1264 2500);
DISPLAY 0.638298 (1264 2500);
PAINT MONO (1264 2500);
FORCEPROP 2 LAST PATH I77
J 0
(1250 2575);
DISPLAY 1.021277 (1250 2575);
PAINT ORANGE (1250 2575);
DISPLAY INVISIBLE (1250 2575);
FORCEPROP 2 LAST CDS_LIB mstr_standard
J 0
(1075 2500);
PAINT MONO (1075 2500);
DISPLAY INVISIBLE (1075 2500);
FORCEPROP 1 LAST OFFPAGE TRUE
J 0
(1400 2375);
DISPLAY 0.872340 (1400 2375);
PAINT GREEN (1400 2375);
DISPLAY INVISIBLE (1400 2375);
FORCEPROP 1 LAST COMMENT_BODY TRUE
J 0
(1030 2405);
DISPLAY 0.872340 (1030 2405);
PAINT GREEN (1030 2405);
DISPLAY INVISIBLE (1030 2405);
FORCEADD OFFPAGE..2
(1075 2550);
FORCEPROP 2 LAST $XR2 190 
J 0
(1474 2550);
DISPLAY 0.638298 (1474 2550);
PAINT MONO (1474 2550);
FORCEPROP 2 LAST $XR1 120 
J 0
(1354 2550);
DISPLAY 0.638298 (1354 2550);
PAINT MONO (1354 2550);
FORCEPROP 2 LAST $XR0 92 
J 0
(1264 2550);
DISPLAY 0.638298 (1264 2550);
PAINT MONO (1264 2550);
FORCEPROP 2 LAST PATH I79
J 0
(1250 2625);
DISPLAY 1.021277 (1250 2625);
PAINT ORANGE (1250 2625);
DISPLAY INVISIBLE (1250 2625);
FORCEPROP 2 LAST CDS_LIB mstr_standard
J 0
(1075 2550);
PAINT MONO (1075 2550);
DISPLAY INVISIBLE (1075 2550);
FORCEPROP 1 LAST OFFPAGE TRUE
J 0
(1400 2425);
DISPLAY 0.872340 (1400 2425);
PAINT GREEN (1400 2425);
DISPLAY INVISIBLE (1400 2425);
FORCEPROP 1 LAST COMMENT_BODY TRUE
J 0
(1030 2455);
DISPLAY 0.872340 (1030 2455);
PAINT GREEN (1030 2455);
DISPLAY INVISIBLE (1030 2455);
FORCEADD RES..1
(925 4400);
FORCEPROP 1 LAST TOLERANCE 1.0%
J 2
(1225 4400);
DISPLAY 0.617021 (1225 4400);
PAINT SKYBLUE (1225 4400);
FORCEPROP 1 LASTPIN (1025 4400) $PN 2
J 0
(987 4412);
DISPLAY 0.617021 (987 4412);
PAINT ORANGE (987 4412);
FORCEPROP 1 LASTPIN (825 4400) $PN 1
J 0
(837 4412);
DISPLAY 0.617021 (837 4412);
PAINT ORANGE (837 4412);
FORCEPROP 1 LAST VALUE 22.1
J 0
(1050 4400);
DISPLAY 0.617021 (1050 4400);
PAINT SKYBLUE (1050 4400);
FORCEPROP 1 LAST LOCATION R25W88
J 0
(700 4400);
DISPLAY 0.617021 (700 4400);
PAINT AQUA (700 4400);
FORCEPROP 1 LAST PATH I8
J 0
(875 4550);
DISPLAY 0.978723 (875 4550);
PAINT WHITE (875 4550);
DISPLAY INVISIBLE (875 4550);
FORCEPROP 1 LAST MATERIAL CHIP
J 2
(725 4350);
DISPLAY 0.617021 (725 4350);
PAINT SKYBLUE (725 4350);
DISPLAY INVISIBLE (725 4350);
FORCEPROP 1 LAST PACK_TYPE 0402
J 0
(1175 4250);
DISPLAY 0.978723 (1175 4250);
PAINT SKYBLUE (1175 4250);
DISPLAY INVISIBLE (1175 4250);
FORCEPROP 2 LAST BOM_COST SM_CONTROLLER
J 0
(1125 4500);
DISPLAY 1.021277 (1125 4500);
PAINT ORANGE (1125 4500);
DISPLAY INVISIBLE (1125 4500);
FORCEPROP 2 LAST CDS_LIB mstr_discrete
J 0
(925 4400);
PAINT ORANGE (925 4400);
DISPLAY INVISIBLE (925 4400);
FORCEPROP 2 LAST ROOM BMC
J 0
(1125 4450);
DISPLAY 1.021277 (1125 4450);
PAINT ORANGE (1125 4450);
DISPLAY INVISIBLE (1125 4450);
FORCEPROP 2 LAST SEC_TYPE 0402
J 0
(875 4600);
DISPLAY 1.021277 (875 4600);
PAINT ORANGE (875 4600);
DISPLAY INVISIBLE (875 4600);
FORCEPROP 2 LAST SEC 1
J 0
(875 4600);
DISPLAY 0.680851 (875 4600);
PAINT MONO (875 4600);
DISPLAY INVISIBLE (875 4600);
FORCEPROP 1 LAST PART_NUMBER G21796-250
J 0
(875 4500);
DISPLAY 0.978723 (875 4500);
PAINT BLUE (875 4500);
DISPLAY INVISIBLE (875 4500);
FORCEPROP 1 LAST WATTAGE 1/16W
J 2
(875 4425);
DISPLAY 0.978723 (875 4425);
PAINT SKYBLUE (875 4425);
DISPLAY INVISIBLE (875 4425);
FORCEPROP 0 LAST CDS_SEC 1
J 0
(1075 4450);
PAINT MONO (1075 4450);
DISPLAY INVISIBLE (1075 4450);
FORCEPROP 2 LAST CDS_LOCATION R25W88
J 0
(875 4350);
DISPLAY 0.617021 (875 4350);
PAINT AQUA (875 4350);
DISPLAY INVISIBLE (875 4350);
FORCEADD OFFPAGE..2
(1075 2600);
FORCEPROP 2 LAST $XR1 154 
J 0
(1384 2600);
DISPLAY 0.638298 (1384 2600);
PAINT MONO (1384 2600);
FORCEPROP 2 LAST $XR0 120 
J 0
(1264 2600);
DISPLAY 0.638298 (1264 2600);
PAINT MONO (1264 2600);
FORCEPROP 2 LAST CDS_LIB mstr_standard
J 0
(1075 2600);
PAINT MONO (1075 2600);
DISPLAY INVISIBLE (1075 2600);
FORCEPROP 2 LAST PATH I81
J 0
(1250 2675);
DISPLAY 1.021277 (1250 2675);
PAINT ORANGE (1250 2675);
DISPLAY INVISIBLE (1250 2675);
FORCEPROP 1 LAST OFFPAGE TRUE
J 0
(1400 2475);
DISPLAY 0.872340 (1400 2475);
PAINT GREEN (1400 2475);
DISPLAY INVISIBLE (1400 2475);
FORCEPROP 1 LAST COMMENT_BODY TRUE
J 0
(1030 2505);
DISPLAY 0.872340 (1030 2505);
PAINT GREEN (1030 2505);
DISPLAY INVISIBLE (1030 2505);
FORCEADD OFFPAGE..2
(1075 2750);
FORCEPROP 2 LAST $XR0 190 
J 0
(1264 2750);
DISPLAY 0.638298 (1264 2750);
PAINT MONO (1264 2750);
FORCEPROP 2 LAST $XR2 158 
J 0
(1504 2750);
DISPLAY 0.638298 (1504 2750);
PAINT MONO (1504 2750);
FORCEPROP 2 LAST $XR1 120 
J 0
(1384 2750);
DISPLAY 0.638298 (1384 2750);
PAINT MONO (1384 2750);
FORCEPROP 2 LAST CDS_LIB mstr_standard
J 0
(1075 2750);
PAINT MONO (1075 2750);
DISPLAY INVISIBLE (1075 2750);
FORCEPROP 2 LAST PATH I84
J 0
(1250 2825);
DISPLAY 1.021277 (1250 2825);
PAINT ORANGE (1250 2825);
DISPLAY INVISIBLE (1250 2825);
FORCEPROP 1 LAST OFFPAGE TRUE
J 0
(1400 2625);
DISPLAY 0.872340 (1400 2625);
PAINT GREEN (1400 2625);
DISPLAY INVISIBLE (1400 2625);
FORCEPROP 1 LAST COMMENT_BODY TRUE
J 0
(1030 2655);
DISPLAY 0.872340 (1030 2655);
PAINT GREEN (1030 2655);
DISPLAY INVISIBLE (1030 2655);
FORCEADD OFFPAGE..2
(1075 2700);
FORCEPROP 2 LAST $XR0 190 
J 0
(1264 2700);
DISPLAY 0.638298 (1264 2700);
PAINT MONO (1264 2700);
FORCEPROP 2 LAST $XR2 158 
J 0
(1504 2700);
DISPLAY 0.638298 (1504 2700);
PAINT MONO (1504 2700);
FORCEPROP 2 LAST $XR1 120 
J 0
(1384 2700);
DISPLAY 0.638298 (1384 2700);
PAINT MONO (1384 2700);
FORCEPROP 2 LAST CDS_LIB mstr_standard
J 0
(1075 2700);
PAINT MONO (1075 2700);
DISPLAY INVISIBLE (1075 2700);
FORCEPROP 2 LAST PATH I85
J 0
(1250 2775);
DISPLAY 1.021277 (1250 2775);
PAINT ORANGE (1250 2775);
DISPLAY INVISIBLE (1250 2775);
FORCEPROP 1 LAST OFFPAGE TRUE
J 0
(1400 2575);
DISPLAY 0.872340 (1400 2575);
PAINT GREEN (1400 2575);
DISPLAY INVISIBLE (1400 2575);
FORCEPROP 1 LAST COMMENT_BODY TRUE
J 0
(1030 2605);
DISPLAY 0.872340 (1030 2605);
PAINT GREEN (1030 2605);
DISPLAY INVISIBLE (1030 2605);
FORCEADD OFFPAGE..1
(-4650 2550);
FORCEPROP 2 LAST $XR0 168 
J 0
(-5076 2550);
DISPLAY 0.638298 (-5076 2550);
PAINT MONO (-5076 2550);
DISPLAY INVISIBLE (-5076 2550);
FORCEPROP 2 LAST $XR1 119 
J 0
(-5076 2550);
DISPLAY 0.638298 (-5076 2550);
PAINT MONO (-5076 2550);
DISPLAY INVISIBLE (-5076 2550);
FORCEPROP 2 LAST $XR2 120 
J 0
(-5076 2550);
DISPLAY 0.638298 (-5076 2550);
PAINT MONO (-5076 2550);
DISPLAY INVISIBLE (-5076 2550);
FORCEPROP 1 LAST COMMENT_BODY TRUE
J 0
(-4525 2450);
DISPLAY 0.872340 (-4525 2450);
PAINT GREEN (-4525 2450);
DISPLAY INVISIBLE (-4525 2450);
FORCEPROP 1 LAST OFFPAGE TRUE
J 0
(-4325 2425);
DISPLAY 0.872340 (-4325 2425);
PAINT GREEN (-4325 2425);
DISPLAY INVISIBLE (-4325 2425);
FORCEPROP 2 LAST CDS_LIB mstr_standard
J 0
(-4650 2550);
PAINT MONO (-4650 2550);
DISPLAY INVISIBLE (-4650 2550);
FORCEPROP 2 LAST PATH I86
J 0
(-4600 2625);
DISPLAY 1.021277 (-4600 2625);
PAINT ORANGE (-4600 2625);
DISPLAY INVISIBLE (-4600 2625);
FORCEADD OFFPAGE..5
(-4675 2600);
FORCEPROP 2 LAST $XR2 120 
J 0
(-5170 2600);
DISPLAY 0.638298 (-5170 2600);
PAINT MONO (-5170 2600);
FORCEPROP 2 LAST $XR0 157 
J 0
(-4930 2600);
DISPLAY 0.638298 (-4930 2600);
PAINT MONO (-4930 2600);
FORCEPROP 2 LAST $XR1 181 
J 0
(-5050 2600);
DISPLAY 0.638298 (-5050 2600);
PAINT MONO (-5050 2600);
FORCEPROP 1 LAST COMMENT_BODY TRUE
J 0
(-4575 2525);
DISPLAY 0.872340 (-4575 2525);
PAINT GREEN (-4575 2525);
DISPLAY INVISIBLE (-4575 2525);
FORCEPROP 1 LAST OFFPAGE TRUE
J 0
(-4350 2475);
DISPLAY 0.872340 (-4350 2475);
PAINT GREEN (-4350 2475);
DISPLAY INVISIBLE (-4350 2475);
FORCEPROP 2 LAST CDS_LIB mstr_standard
J 0
(-4675 2600);
PAINT MONO (-4675 2600);
DISPLAY INVISIBLE (-4675 2600);
FORCEPROP 2 LAST PATH I87
J 0
(-4925 2650);
DISPLAY 1.021277 (-4925 2650);
PAINT ORANGE (-4925 2650);
DISPLAY INVISIBLE (-4925 2650);
FORCEADD OFFPAGE..1
(-4675 2700);
FORCEPROP 2 LAST $XR0 133 
J 0
(-4957 2700);
DISPLAY 0.638298 (-4957 2700);
PAINT MONO (-4957 2700);
FORCEPROP 2 LAST $XR1 182 
J 0
(-5077 2700);
DISPLAY 0.638298 (-5077 2700);
PAINT MONO (-5077 2700);
FORCEPROP 2 LAST $XR2 119 
J 0
(-5197 2700);
DISPLAY 0.638298 (-5197 2700);
PAINT MONO (-5197 2700);
FORCEPROP 1 LAST COMMENT_BODY TRUE
J 0
(-4550 2600);
DISPLAY 0.872340 (-4550 2600);
PAINT GREEN (-4550 2600);
DISPLAY INVISIBLE (-4550 2600);
FORCEPROP 1 LAST OFFPAGE TRUE
J 0
(-4350 2575);
DISPLAY 0.872340 (-4350 2575);
PAINT GREEN (-4350 2575);
DISPLAY INVISIBLE (-4350 2575);
FORCEPROP 2 LAST PATH I88
J 0
(-4950 2750);
DISPLAY 1.021277 (-4950 2750);
PAINT ORANGE (-4950 2750);
DISPLAY INVISIBLE (-4950 2750);
FORCEPROP 2 LAST CDS_LIB mstr_standard
J 0
(-4675 2700);
PAINT MONO (-4675 2700);
DISPLAY INVISIBLE (-4675 2700);
FORCEADD OFFPAGE..1
(-4675 2650);
FORCEPROP 2 LAST $XR0 133 
J 0
(-4927 2650);
DISPLAY 0.638298 (-4927 2650);
PAINT MONO (-4927 2650);
FORCEPROP 2 LAST $XR1 182 
J 0
(-5047 2650);
DISPLAY 0.638298 (-5047 2650);
PAINT MONO (-5047 2650);
FORCEPROP 2 LAST $XR2 119 
J 0
(-5167 2650);
DISPLAY 0.638298 (-5167 2650);
PAINT MONO (-5167 2650);
FORCEPROP 1 LAST COMMENT_BODY TRUE
J 0
(-4550 2550);
DISPLAY 0.872340 (-4550 2550);
PAINT GREEN (-4550 2550);
DISPLAY INVISIBLE (-4550 2550);
FORCEPROP 1 LAST OFFPAGE TRUE
J 0
(-4350 2525);
DISPLAY 0.872340 (-4350 2525);
PAINT GREEN (-4350 2525);
DISPLAY INVISIBLE (-4350 2525);
FORCEPROP 2 LAST PATH I89
J 0
(-4925 2700);
DISPLAY 1.021277 (-4925 2700);
PAINT ORANGE (-4925 2700);
DISPLAY INVISIBLE (-4925 2700);
FORCEPROP 2 LAST CDS_LIB mstr_standard
J 0
(-4675 2650);
PAINT MONO (-4675 2650);
DISPLAY INVISIBLE (-4675 2650);
FORCEADD OFFPAGE..2
(2300 4300);
FORCEPROP 2 LAST $XR0 151 
J 0
(2489 4300);
DISPLAY 0.638298 (2489 4300);
PAINT MONO (2489 4300);
FORCEPROP 2 LAST CDS_LIB mstr_standard
J 0
(2300 4300);
PAINT MONO (2300 4300);
DISPLAY INVISIBLE (2300 4300);
FORCEPROP 2 LAST PATH I9
J 0
(2500 4350);
DISPLAY 1.021277 (2500 4350);
PAINT ORANGE (2500 4350);
DISPLAY INVISIBLE (2500 4350);
FORCEPROP 1 LAST OFFPAGE TRUE
J 0
(2625 4175);
DISPLAY 0.872340 (2625 4175);
PAINT GREEN (2625 4175);
DISPLAY INVISIBLE (2625 4175);
FORCEPROP 1 LAST COMMENT_BODY TRUE
J 0
(2255 4205);
DISPLAY 0.872340 (2255 4205);
PAINT GREEN (2255 4205);
DISPLAY INVISIBLE (2255 4205);
FORCEADD OFFPAGE..1
(-4650 3000);
FORCEPROP 2 LAST $XR1 120 
J 0
(-4902 3036);
DISPLAY 0.638298 (-4902 3036);
PAINT MONO (-4902 3036);
FORCEPROP 2 LAST $XR0 164 
J 0
(-4902 3000);
DISPLAY 0.638298 (-4902 3000);
PAINT MONO (-4902 3000);
FORCEPROP 1 LAST COMMENT_BODY TRUE
J 0
(-4525 2900);
DISPLAY 0.872340 (-4525 2900);
PAINT GREEN (-4525 2900);
DISPLAY INVISIBLE (-4525 2900);
FORCEPROP 1 LAST OFFPAGE TRUE
J 0
(-4325 2875);
DISPLAY 0.872340 (-4325 2875);
PAINT GREEN (-4325 2875);
DISPLAY INVISIBLE (-4325 2875);
FORCEPROP 2 LAST CDS_LIB mstr_standard
J 0
(-4650 3000);
PAINT MONO (-4650 3000);
DISPLAY INVISIBLE (-4650 3000);
FORCEPROP 2 LAST PATH I91
J 0
(-4900 3075);
DISPLAY 1.021277 (-4900 3075);
PAINT ORANGE (-4900 3075);
DISPLAY INVISIBLE (-4900 3075);
FORCEADD OFFPAGE..1
(-4650 2950);
FORCEPROP 2 LAST $XR1 120 
J 0
(-4902 2914);
DISPLAY 0.638298 (-4902 2914);
PAINT MONO (-4902 2914);
FORCEPROP 2 LAST $XR0 164 
J 0
(-4902 2950);
DISPLAY 0.638298 (-4902 2950);
PAINT MONO (-4902 2950);
FORCEPROP 1 LAST COMMENT_BODY TRUE
J 0
(-4525 2850);
DISPLAY 0.872340 (-4525 2850);
PAINT GREEN (-4525 2850);
DISPLAY INVISIBLE (-4525 2850);
FORCEPROP 1 LAST OFFPAGE TRUE
J 0
(-4325 2825);
DISPLAY 0.872340 (-4325 2825);
PAINT GREEN (-4325 2825);
DISPLAY INVISIBLE (-4325 2825);
FORCEPROP 2 LAST PATH I92
J 0
(-4900 3000);
DISPLAY 1.021277 (-4900 3000);
PAINT ORANGE (-4900 3000);
DISPLAY INVISIBLE (-4900 3000);
FORCEPROP 2 LAST CDS_LIB mstr_standard
J 0
(-4650 2950);
PAINT MONO (-4650 2950);
DISPLAY INVISIBLE (-4650 2950);
FORCEADD OFFPAGE..1
(-4650 2900);
FORCEPROP 1 LAST COMMENT_BODY TRUE
J 0
(-4525 2800);
DISPLAY 0.872340 (-4525 2800);
PAINT GREEN (-4525 2800);
DISPLAY INVISIBLE (-4525 2800);
FORCEPROP 1 LAST OFFPAGE TRUE
J 0
(-4325 2775);
DISPLAY 0.872340 (-4325 2775);
PAINT GREEN (-4325 2775);
DISPLAY INVISIBLE (-4325 2775);
FORCEPROP 2 LAST PATH I93
J 0
(-4600 2975);
DISPLAY 1.021277 (-4600 2975);
PAINT ORANGE (-4600 2975);
DISPLAY INVISIBLE (-4600 2975);
FORCEPROP 2 LAST CDS_LIB mstr_standard
J 0
(-4650 2900);
PAINT MONO (-4650 2900);
DISPLAY INVISIBLE (-4650 2900);
FORCEPROP 2 LAST $XR1 120 
J 0
(-5076 2900);
DISPLAY 0.638298 (-5076 2900);
PAINT MONO (-5076 2900);
DISPLAY INVISIBLE (-5076 2900);
FORCEPROP 2 LAST $XR0 164 
J 0
(-5076 2900);
DISPLAY 0.638298 (-5076 2900);
PAINT MONO (-5076 2900);
DISPLAY INVISIBLE (-5076 2900);
FORCEADD OFFPAGE..1
(-4650 2850);
FORCEPROP 2 LAST $XR0 164 
J 0
(-4902 2850);
DISPLAY 0.638298 (-4902 2850);
PAINT MONO (-4902 2850);
FORCEPROP 2 LAST $XR1 120 
J 0
(-4902 2814);
DISPLAY 0.638298 (-4902 2814);
PAINT MONO (-4902 2814);
FORCEPROP 1 LAST COMMENT_BODY TRUE
J 0
(-4525 2750);
DISPLAY 0.872340 (-4525 2750);
PAINT GREEN (-4525 2750);
DISPLAY INVISIBLE (-4525 2750);
FORCEPROP 1 LAST OFFPAGE TRUE
J 0
(-4325 2725);
DISPLAY 0.872340 (-4325 2725);
PAINT GREEN (-4325 2725);
DISPLAY INVISIBLE (-4325 2725);
FORCEPROP 2 LAST PATH I94
J 0
(-4900 2900);
DISPLAY 1.021277 (-4900 2900);
PAINT ORANGE (-4900 2900);
DISPLAY INVISIBLE (-4900 2900);
FORCEPROP 2 LAST CDS_LIB mstr_standard
J 0
(-4650 2850);
PAINT MONO (-4650 2850);
DISPLAY INVISIBLE (-4650 2850);
FORCEADD OFFPAGE..1
(-4650 3050);
FORCEPROP 2 LAST $XR0 164 
J 0
(-5112 3050);
DISPLAY 0.638298 (-5112 3050);
PAINT MONO (-5112 3050);
FORCEPROP 2 LAST $XR1 120 
J 0
(-5232 3050);
DISPLAY 0.638298 (-5232 3050);
PAINT MONO (-5232 3050);
FORCEPROP 1 LAST COMMENT_BODY TRUE
J 0
(-4525 2950);
DISPLAY 0.872340 (-4525 2950);
PAINT GREEN (-4525 2950);
DISPLAY INVISIBLE (-4525 2950);
FORCEPROP 1 LAST OFFPAGE TRUE
J 0
(-4325 2925);
DISPLAY 0.872340 (-4325 2925);
PAINT GREEN (-4325 2925);
DISPLAY INVISIBLE (-4325 2925);
FORCEPROP 2 LAST PATH I95
J 0
(-4600 3125);
DISPLAY 1.021277 (-4600 3125);
PAINT ORANGE (-4600 3125);
DISPLAY INVISIBLE (-4600 3125);
FORCEPROP 2 LAST CDS_LIB mstr_standard
J 0
(-4650 3050);
PAINT MONO (-4650 3050);
DISPLAY INVISIBLE (-4650 3050);
FORCEADD OFFPAGE..4
(1750 4050);
FORCEPROP 2 LAST $XR0 157 
J 0
(1936 4050);
DISPLAY 0.638298 (1936 4050);
PAINT MONO (1936 4050);
FORCEPROP 2 LAST $XR1 119 
J 0
(2056 4050);
DISPLAY 0.638298 (2056 4050);
PAINT MONO (2056 4050);
FORCEPROP 2 LAST CDS_LIB mstr_standard
J 0
(1750 4050);
PAINT ORANGE (1750 4050);
DISPLAY INVISIBLE (1750 4050);
FORCEPROP 2 LAST PATH I96
J 0
(2075 4100);
DISPLAY 1.021277 (2075 4100);
PAINT ORANGE (2075 4100);
DISPLAY INVISIBLE (2075 4100);
FORCEPROP 1 LAST OFFPAGE TRUE
J 0
(2075 3925);
DISPLAY 0.872340 (2075 3925);
PAINT GREEN (2075 3925);
DISPLAY INVISIBLE (2075 3925);
FORCEPROP 1 LAST COMMENT_BODY TRUE
J 0
(1725 3950);
DISPLAY 0.872340 (1725 3950);
PAINT GREEN (1725 3950);
DISPLAY INVISIBLE (1725 3950);
FORCEADD OFFPAGE..1
(-4775 3450);
FORCEPROP 2 LAST $XR0 21 
J 0
(-4996 3450);
DISPLAY 0.638298 (-4996 3450);
PAINT MONO (-4996 3450);
FORCEPROP 2 LAST $XR1 190 
J 0
(-5116 3450);
DISPLAY 0.638298 (-5116 3450);
PAINT MONO (-5116 3450);
FORCEPROP 2 LAST PATH I99
J 0
(-4725 3525);
DISPLAY 1.021277 (-4725 3525);
PAINT ORANGE (-4725 3525);
DISPLAY INVISIBLE (-4725 3525);
FORCEPROP 2 LAST CDS_LIB mstr_standard
J 0
(-4775 3450);
PAINT MONO (-4775 3450);
DISPLAY INVISIBLE (-4775 3450);
FORCEPROP 2 LAST BOM_COST SM_CONTROLLER
J 0
(-4325 3500);
PAINT MONO (-4325 3500);
DISPLAY INVISIBLE (-4325 3500);
FORCEPROP 2 LAST ROOM BMC
J 0
(-5025 3525);
DISPLAY 1.361702 (-5025 3525);
PAINT ORANGE (-5025 3525);
DISPLAY INVISIBLE (-5025 3525);
FORCEPROP 1 LAST OFFPAGE TRUE
J 0
(-4450 3325);
DISPLAY 0.872340 (-4450 3325);
PAINT GREEN (-4450 3325);
DISPLAY INVISIBLE (-4450 3325);
FORCEPROP 1 LAST COMMENT_BODY TRUE
J 0
(-4650 3350);
DISPLAY 0.872340 (-4650 3350);
PAINT GREEN (-4650 3350);
DISPLAY INVISIBLE (-4650 3350);
FORCEADD INTEL_CORP_BPAGE..1
(2750 500);
FORCEPROP 1 LAST CDS_CON_LAST_MODIFIED Tue Dec 01 11:52:05 2015
J 0
(1325 825);
DISPLAY 1.361702 (1325 825);
PAINT GREEN (1325 825);
DISPLAY INVISIBLE (1325 825);
FORCEPROP 2 LAST CUSTOM_TXT_CDS <XR_PAGE_TITLE>
J 0
(-5140 5750);
DISPLAY 0.638298 (-5140 5750);
PAINT PINK (-5140 5750);
DISPLAY INVISIBLE (-5140 5750);
FORCEPROP 2 LAST CUSTOM_TXT_CDS <CON_LAST_MODIFIED>
J 0
(825 850);
PAINT ORANGE (825 850);
FORCEPROP 2 LAST CUSTOM_TXT_CDS <CURRENT_DESIGN_SHEET> OF <TOTAL_DESIGN_SHEETS>
J 0
(2250 525);
PAINT ORANGE (2250 525);
FORCEPROP 1 LAST SCH_ADDRESS1 2200 Mission College Blvd.
J 0
(-1225 625);
DISPLAY 0.617021 (-1225 625);
PAINT GREEN (-1225 625);
FORCEPROP 1 LAST SCH_DEPT BESD
J 1
(-1700 600);
DISPLAY 1.212766 (-1700 600);
PAINT YELLOW (-1700 600);
FORCEPROP 1 LAST SCH_ADDRESS2 P.O. BOX 58119
J 0
(-1225 575);
DISPLAY 0.617021 (-1225 575);
PAINT GREEN (-1225 575);
FORCEPROP 1 LAST SCH_REV 2.420
J 0
(2500 650);
DISPLAY 0.978723 (2500 650);
PAINT YELLOW (2500 650);
FORCEPROP 1 LAST SCH_NUMBER H4694802
J 0
(1450 650);
DISPLAY 1.212766 (1450 650);
PAINT YELLOW (1450 650);
FORCEPROP 1 LAST SCH_ADDRESS3 Santa Clara, CA 95052-8119
J 0
(-1225 525);
DISPLAY 0.617021 (-1225 525);
PAINT GREEN (-1225 525);
FORCEPROP 1 LAST SCH_TITLE BMC (6 OF 7)
J 0
(-5200 550);
DISPLAY 1.212766 (-5200 550);
PAINT ORANGE (-5200 550);
FORCEPROP 2 LAST PAGE_BORDER TRUE
J 0
(-5140 5750);
DISPLAY 0.851064 (-5140 5750);
PAINT PINK (-5140 5750);
DISPLAY INVISIBLE (-5140 5750);
FORCEPROP 2 LAST CDS_LIB mstr_symbols
J 0
(2750 500);
PAINT MONO (2750 500);
DISPLAY INVISIBLE (2750 500);
FORCEPROP 1 LAST COMMENT_BODY TRUE
J 0
(2762 512);
DISPLAY 0.617021 (2762 512);
PAINT GREEN (2762 512);
DISPLAY INVISIBLE (2762 512);
FORCEPROP 2 LAST CDS_XR_PAGE_TITLE CR-147 : @BASEBOARD_FAB2_LIB.BASEBOARD_FAB2(SCH_1):PAGE147
J 0
(-5140 5750);
DISPLAY 0.638298 (-5140 5750);
PAINT PINK (-5140 5750);
DISPLAY INVISIBLE (-5140 5750);
FORCEADD DNS..2
(2005 2295);
PAINT RED (2005 2295);
FORCEPROP 2 LAST CDS_LIB mstr_misc
J 0
(2005 2295);
PAINT ORANGE (2005 2295);
DISPLAY INVISIBLE (2005 2295);
FORCEPROP 1 LAST COMMENT_BODY TRUE
R 1
J 0
(2080 2070);
DISPLAY 0.872340 (2080 2070);
PAINT GREEN (2080 2070);
DISPLAY INVISIBLE (2080 2070);
FORCEADD DNS..2
(2005 1945);
PAINT RED (2005 1945);
FORCEPROP 2 LAST CDS_LIB mstr_misc
J 0
(2005 1945);
PAINT ORANGE (2005 1945);
DISPLAY INVISIBLE (2005 1945);
FORCEPROP 1 LAST COMMENT_BODY TRUE
R 1
J 0
(2080 1720);
DISPLAY 0.872340 (2080 1720);
PAINT GREEN (2080 1720);
DISPLAY INVISIBLE (2080 1720);
FORCEADD CAD_NOTE..1
(1075 5100);
FORCEPROP 0 LAST L2 NEAR BMC
J 0
(925 4950);
DISPLAY 0.808511 (925 4950);
PAINT ORANGE (925 4950);
FORCEPROP 0 LAST L1 PLACE THESE RESISTORS
J 0
(925 5000);
DISPLAY 0.808511 (925 5000);
PAINT ORANGE (925 5000);
FORCEPROP 2 LAST CDS_LIB mstr_symbols
J 0
(1075 5100);
PAINT ORANGE (1075 5100);
DISPLAY INVISIBLE (1075 5100);
FORCEPROP 1 LAST COMMENT_BODY TRUE
J 0
(1100 5200);
DISPLAY 0.978723 (1100 5200);
PAINT ORANGE (1100 5200);
DISPLAY INVISIBLE (1100 5200);
FORCEADD DNS..2
(1630 2120);
PAINT RED (1630 2120);
FORCEPROP 2 LAST CDS_LIB mstr_misc
J 0
(1630 2120);
PAINT ORANGE (1630 2120);
DISPLAY INVISIBLE (1630 2120);
FORCEPROP 1 LAST COMMENT_BODY TRUE
R 1
J 0
(1705 1895);
DISPLAY 0.872340 (1705 1895);
PAINT GREEN (1705 1895);
DISPLAY INVISIBLE (1705 1895);
WIRE 16 -1 (2100 2300)(2350 2300);
FORCEPROP 0 LAST VOLTAGE +3.3V
J 0
(2283 2340);
PAINT MONO (2283 2340);
DISPLAY INVISIBLE (2283 2340);
FORCEPROP 0 LAST CDS_PHYS_NET_NAME P3V3_STBY_BMC_ADCAV33
J 0
(2283 2387);
PAINT MONO (2283 2387);
DISPLAY INVISIBLE (2283 2387);
WIRE 16 -1 (2350 2525)(2350 2300);
WIRE 16 -1 (2100 1950)(2325 1950);
WIRE 16 -1 (2325 1900)(2325 1950);
WIRE 16 -1 (775 1825)(775 1725);
WIRE 16 -1 (-3650 4900)(-3650 5000);
WIRE 16 -1 (-3650 5000)(-3900 5000);
WIRE 16 -1 (-3900 4900)(-3900 5000);
WIRE 16 -1 (-3900 5000)(-3900 5050);
WIRE 16 -1 (-3525 4650)(-3375 4650);
WIRE 16 -1 (-3525 4400)(-3525 4650);
WIRE 16 -1 (-3375 4400)(-3525 4400);
WIRE 16 -1 (-3525 3650)(-3525 4400);
WIRE 16 -1 (2200 4850)(2200 4975);
WIRE 16 -1 (2200 4975)(1950 4975);
WIRE 16 -1 (1950 4875)(1950 4975);
WIRE 16 -1 (1950 4975)(1950 5050);
WIRE 16 -1 (-3525 1775)(-3525 1850);
WIRE 16 -1 (-3775 1775)(-3775 1850);
WIRE 16 -1 (-4025 1775)(-4025 1850);
WIRE 16 -1 (-4275 1775)(-4275 1850);
WIRE 16 -1 (-100 1625)(-100 1725);
WIRE 16 -1 (-275 3100)(1000 3100);
FORCEPROP 2 LAST SIG_NAME A_P12V_STBY_SCALED
J 0
(-75 3110);
DISPLAY 0.680851 (-75 3110);
PAINT ORANGE (-75 3110);
WIRE 16 -1 (-275 3150)(1000 3150);
FORCEPROP 2 LAST SIG_NAME A_P3V3_STBY_SCALED
J 0
(-75 3160);
DISPLAY 0.680851 (-75 3160);
PAINT ORANGE (-75 3160);
WIRE 16 -1 (-275 3200)(1000 3200);
FORCEPROP 2 LAST SIG_NAME A_P3V_BAT_SCALED
J 0
(-75 3210);
DISPLAY 0.680851 (-75 3210);
PAINT ORANGE (-75 3210);
WIRE 16 -1 (-4600 2500)(-3525 2500);
FORCEPROP 2 LAST SIG_NAME FAN_TACH3
J 0
(-4450 2510);
DISPLAY 0.680851 (-4450 2510);
PAINT ORANGE (-4450 2510);
WIRE 16 -1 (-3525 2500)(-3375 2500);
WIRE 16 -1 (-3525 2050)(-3525 2500);
WIRE 16 -1 (-4600 2550)(-3375 2550);
FORCEPROP 2 LAST SIG_NAME FM_POST_CARD_PRES_BMC_N
J 0
(-4450 2560);
DISPLAY 0.680851 (-4450 2560);
PAINT ORANGE (-4450 2560);
WIRE 16 -1 (-4600 2900)(-3375 2900);
FORCEPROP 2 LAST SIG_NAME FM_BOARD_SKU_ID1
J 0
(-4460 2910);
DISPLAY 0.680851 (-4460 2910);
PAINT ORANGE (-4460 2910);
WIRE 16 -1 (-4725 4050)(-3375 4050);
FORCEPROP 2 LAST SIG_NAME CLK_50M_CKMNG_BMC_1
J 0
(-4600 4060);
DISPLAY 0.680851 (-4600 4060);
PAINT ORANGE (-4600 4060);
WIRE 16 -1 (-3375 4150)(-3650 4150);
WIRE 16 -1 (-3650 4150)(-3650 4700);
WIRE 16 -1 (-4725 4150)(-3650 4150);
FORCEPROP 2 LAST SIG_NAME RMII_SPRNGVLLE_BMC_PCH_RXD0
J 0
(-4600 4160);
DISPLAY 0.680851 (-4600 4160);
PAINT ORANGE (-4600 4160);
WIRE 16 -1 (-3375 4200)(-3900 4200);
WIRE 16 -1 (-3900 4700)(-3900 4200);
WIRE 16 -1 (-4725 4200)(-3900 4200);
FORCEPROP 2 LAST SIG_NAME RMII_SPRNGVLLE_BMC_PCH_RXD1
J 0
(-4600 4210);
DISPLAY 0.680851 (-4600 4210);
PAINT ORANGE (-4600 4210);
WIRE 16 -1 (-4725 4250)(-3375 4250);
FORCEPROP 2 LAST SIG_NAME RMII_BMC_PCH_SPRNGVLLE_CRSDV
J 0
(-4600 4260);
DISPLAY 0.680851 (-4600 4260);
PAINT ORANGE (-4600 4260);
WIRE 16 -1 (-4725 4300)(-3375 4300);
FORCEPROP 2 LAST SIG_NAME RMII_BMC_PCH_SPRNGVLLE_RXER
J 0
(-4600 4310);
DISPLAY 0.680851 (-4600 4310);
PAINT ORANGE (-4600 4310);
WIRE 16 -1 (-3375 4450)(-4725 4450);
FORCEPROP 2 LAST SIG_NAME CLK_50M_CKMNG_BMC_2
J 0
(-4585 4460);
DISPLAY 0.680851 (-4585 4460);
PAINT ORANGE (-4585 4460);
WIRE 16 -1 (-4725 3900)(-3375 3900);
FORCEPROP 2 LAST SIG_NAME RMII_BMC_OCP_RXER
J 0
(-4600 3910);
DISPLAY 0.680851 (-4600 3910);
PAINT ORANGE (-4600 3910);
WIRE 16 -1 (-4725 3800)(-3375 3800);
FORCEPROP 2 LAST SIG_NAME RMII_BMC_OCP_RXD1
J 0
(-4600 3810);
DISPLAY 0.680851 (-4600 3810);
PAINT ORANGE (-4600 3810);
WIRE 16 -1 (-4725 3750)(-3375 3750);
FORCEPROP 2 LAST SIG_NAME RMII_BMC_OCP_RXD0
J 0
(-4600 3760);
DISPLAY 0.680851 (-4600 3760);
PAINT ORANGE (-4600 3760);
WIRE 16 -1 (-3375 3100)(-4600 3100);
FORCEPROP 2 LAST SIG_NAME FM_TPM_PRES_N
J 0
(-4460 3110);
DISPLAY 0.680851 (-4460 3110);
PAINT ORANGE (-4460 3110);
WIRE 16 -1 (-4275 2050)(-4275 2350);
WIRE 16 -1 (-4275 2350)(-3375 2350);
WIRE 16 -1 (-4600 2350)(-4275 2350);
FORCEPROP 2 LAST SIG_NAME FAN_TACH0
J 0
(-4450 2360);
DISPLAY 0.680851 (-4450 2360);
PAINT ORANGE (-4450 2360);
WIRE 16 -1 (-4025 2050)(-4025 2400);
WIRE 16 -1 (-4025 2400)(-3375 2400);
WIRE 16 -1 (-4600 2400)(-4025 2400);
FORCEPROP 2 LAST SIG_NAME FAN_TACH1
J 0
(-4450 2410);
DISPLAY 0.680851 (-4450 2410);
PAINT ORANGE (-4450 2410);
WIRE 16 -1 (-3775 2050)(-3775 2450);
WIRE 16 -1 (-3775 2450)(-3375 2450);
WIRE 16 -1 (-4600 2450)(-3775 2450);
FORCEPROP 2 LAST SIG_NAME FAN_TACH2
J 0
(-4450 2460);
DISPLAY 0.680851 (-4450 2460);
PAINT ORANGE (-4450 2460);
WIRE 16 -1 (-4625 2600)(-3375 2600);
FORCEPROP 2 LAST SIG_NAME FM_MP_PS_REDUNDANT_LOST_N
J 0
(-4460 2610);
DISPLAY 0.680851 (-4460 2610);
PAINT ORANGE (-4460 2610);
WIRE 16 -1 (-4625 2650)(-3375 2650);
FORCEPROP 2 LAST SIG_NAME FM_XRC_PRESENT_N
J 0
(-4460 2660);
DISPLAY 0.680851 (-4460 2660);
PAINT ORANGE (-4460 2660);
WIRE 16 -1 (-4625 2700)(-3375 2700);
FORCEPROP 2 LAST SIG_NAME FM_XRC_READY_N
J 0
(-4460 2710);
DISPLAY 0.680851 (-4460 2710);
PAINT ORANGE (-4460 2710);
WIRE 16 -1 (-3375 2750)(-4625 2750);
FORCEPROP 2 LAST SIG_NAME BMC_TPM_HW_RST
J 0
(-4460 2760);
DISPLAY 0.680851 (-4460 2760);
PAINT ORANGE (-4460 2760);
WIRE 16 -1 (-4625 2800)(-3375 2800);
FORCEPROP 2 LAST SIG_NAME BMC_UV_HIGH_SET
J 0
(-4460 2810);
DISPLAY 0.680851 (-4460 2810);
PAINT ORANGE (-4460 2810);
WIRE 16 -1 (-4600 2850)(-3375 2850);
FORCEPROP 2 LAST SIG_NAME FM_BOARD_SKU_ID0
J 0
(-4460 2860);
DISPLAY 0.680851 (-4460 2860);
PAINT ORANGE (-4460 2860);
WIRE 16 -1 (-3375 2950)(-4600 2950);
FORCEPROP 2 LAST SIG_NAME FM_BOARD_SKU_ID2
J 0
(-4460 2960);
DISPLAY 0.680851 (-4460 2960);
PAINT ORANGE (-4460 2960);
WIRE 16 -1 (-4600 3000)(-3375 3000);
FORCEPROP 2 LAST SIG_NAME FM_BOARD_SKU_ID3
J 0
(-4460 3010);
DISPLAY 0.680851 (-4460 3010);
PAINT ORANGE (-4460 3010);
WIRE 16 -1 (-4600 3050)(-3375 3050);
FORCEPROP 2 LAST SIG_NAME FM_BOARD_SKU_ID4
J 2
(-4050 3060);
DISPLAY 0.680851 (-4050 3060);
PAINT ORANGE (-4050 3060);
WIRE 16 -1 (-4725 4000)(-3375 4000);
FORCEPROP 0 LAST SIG_NAME H_CPU1_MEMKLM_MEMHOT_LVT3_BMC_N
J 0
(-4600 4010);
DISPLAY 0.680851 (-4600 4010);
PAINT ORANGE (-4600 4010);
WIRE 16 -1 (-4725 3850)(-3375 3850);
FORCEPROP 2 LAST SIG_NAME RMII_BMC_OCP_CRSDV
J 0
(-4600 3860);
DISPLAY 0.680851 (-4600 3860);
PAINT ORANGE (-4600 3860);
WIRE 16 -1 (-4725 3500)(-3375 3500);
FORCEPROP 2 LAST SIG_NAME FM_CPU0_PROC_ID0
J 0
(-4575 3510);
DISPLAY 0.680851 (-4575 3510);
PAINT ORANGE (-4575 3510);
WIRE 16 -1 (-275 3900)(1725 3900);
FORCEPROP 2 LAST SIG_NAME TP_RGMII1TXD3_GPIOT5
J 2
(1725 3910);
DISPLAY 0.680851 (1725 3910);
PAINT ORANGE (1725 3910);
WIRE 16 -1 (-275 4000)(775 4000);
FORCEPROP 2 LAST SIG_NAME RMII_BMC_OCP_TXEN_R
J 0
(-60 4010);
DISPLAY 0.680851 (-60 4010);
PAINT ORANGE (-60 4010);
FORCEPROP 2 LASTPROP $XRERR UNIQUE?
J 0
(-300 4010);
DISPLAY 0.638298 (-300 4010);
PAINT MONO (-300 4010);
DISPLAY INVISIBLE (-300 4010);
WIRE 16 -1 (-275 4050)(1700 4050);
FORCEPROP 0 LAST $PHYS_NET_NAME H_CPU0_FAST_WAKE_LVT3_N
J 0
(1700 4136);
PAINT MONO (1700 4136);
DISPLAY INVISIBLE (1700 4136);
FORCEPROP 0 LAST CDS_PHYS_NET_NAME H_CPU0_FAST_WAKE_LVT3_N
J 0
(1700 4089);
PAINT MONO (1700 4089);
DISPLAY INVISIBLE (1700 4089);
FORCEPROP 2 LAST SIG_NAME H_CPU0_FAST_WAKE_LVT3_N
J 2
(575 4060);
DISPLAY 0.680851 (575 4060);
PAINT ORANGE (575 4060);
WIRE 16 -1 (-275 3850)(1725 3850);
FORCEPROP 2 LAST SIG_NAME TP_RGMII1TXD2_GPIOT4
J 2
(1725 3860);
DISPLAY 0.680851 (1725 3860);
PAINT ORANGE (1725 3860);
WIRE 16 -1 (775 3800)(500 3800);
WIRE 16 -1 (500 3650)(500 3800);
WIRE 16 -1 (500 3800)(-275 3800);
FORCEPROP 2 LAST SIG_NAME RMII_BMC_OCP_TXD1_R
J 0
(-160 3810);
DISPLAY 0.680851 (-160 3810);
PAINT ORANGE (-160 3810);
WIRE 16 -1 (500 3650)(1725 3650);
FORCEPROP 2 LAST SIG_NAME RMII_BMC_OCP_TXD1_R
J 0
(1065 3660);
DISPLAY 0.680851 (1065 3660);
PAINT ORANGE (1065 3660);
WIRE 16 -1 (-275 4200)(675 4200);
FORCEPROP 2 LAST SIG_NAME RMII_BMC_PCH_SPRNGVLLE_TXD1_R
J 0
(-135 4210);
DISPLAY 0.680851 (-135 4210);
PAINT ORANGE (-135 4210);
WIRE 16 -1 (675 4750)(675 4200);
WIRE 16 -1 (825 4200)(675 4200);
WIRE 16 -1 (675 4750)(1350 4750);
FORCEPROP 2 LAST SIG_NAME RMII_BMC_PCH_SPRNGVLLE_TXD1_R
J 0
(715 4760);
DISPLAY 0.617021 (715 4760);
PAINT ORANGE (715 4760);
WIRE 16 -1 (-275 4250)(2250 4250);
FORCEPROP 2 LAST SIG_NAME TP_RGMII2TXD2_GPIOT4
J 2
(475 4260);
DISPLAY 0.680851 (475 4260);
PAINT ORANGE (475 4260);
WIRE 16 -1 (-275 4300)(2250 4300);
FORCEPROP 2 LAST SIG_NAME TP_RGMII2TXD3_GPIOT5
J 2
(475 4310);
DISPLAY 0.680851 (475 4310);
PAINT ORANGE (475 4310);
WIRE 16 -1 (-275 4400)(825 4400);
FORCEPROP 2 LAST SIG_NAME RMII_BMC_SPRNGVLLE_TXEN_R
J 0
(-160 4410);
DISPLAY 0.680851 (-160 4410);
PAINT ORANGE (-160 4410);
FORCEPROP 2 LASTPROP $XRERR UNIQUE?
J 0
(-400 4410);
DISPLAY 0.638298 (-400 4410);
PAINT MONO (-400 4410);
DISPLAY INVISIBLE (-400 4410);
WIRE 16 -1 (-275 4600)(375 4600);
FORCEPROP 2 LAST SIG_NAME FM_FORCE_ADR_N
J 0
(-110 4610);
DISPLAY 0.680851 (-110 4610);
PAINT ORANGE (-110 4610);
WIRE 16 -1 (-275 4650)(375 4650);
FORCEPROP 2 LAST SIG_NAME FM_UV_ADR_TRIGGER_EN
J 0
(-160 4660);
DISPLAY 0.680851 (-160 4660);
PAINT ORANGE (-160 4660);
WIRE 16 -1 (-275 4150)(625 4150);
FORCEPROP 2 LAST SIG_NAME RMII_BMC_PCH_SPRNGVLLE_TXD0_R
J 0
(-135 4160);
DISPLAY 0.680851 (-135 4160);
PAINT ORANGE (-135 4160);
WIRE 16 -1 (625 4150)(625 4875);
WIRE 16 -1 (625 4150)(825 4150);
WIRE 16 -1 (625 4875)(1350 4875);
FORCEPROP 2 LAST SIG_NAME RMII_BMC_PCH_SPRNGVLLE_TXD0_R
J 0
(715 4885);
DISPLAY 0.617021 (715 4885);
PAINT ORANGE (715 4885);
WIRE 16 -1 (-275 3750)(550 3750);
FORCEPROP 2 LAST SIG_NAME RMII_BMC_OCP_TXD0_R
J 0
(-160 3760);
DISPLAY 0.680851 (-160 3760);
PAINT ORANGE (-160 3760);
WIRE 16 -1 (550 3750)(775 3750);
WIRE 16 -1 (550 3700)(550 3750);
WIRE 16 -1 (550 3700)(1725 3700);
FORCEPROP 2 LAST SIG_NAME RMII_BMC_OCP_TXD0_R
J 0
(1065 3710);
DISPLAY 0.680851 (1065 3710);
PAINT ORANGE (1065 3710);
WIRE 16 -1 (-275 2850)(1000 2850);
FORCEPROP 2 LAST SIG_NAME A_P5V_STBY_SCALED
J 0
(-75 2860);
DISPLAY 0.680851 (-75 2860);
PAINT ORANGE (-75 2860);
WIRE 16 -1 (-275 2750)(1025 2750);
FORCEPROP 2 LAST SIG_NAME FM_UARTSW_MSB_N
J 0
(-60 2760);
DISPLAY 0.680851 (-60 2760);
PAINT ORANGE (-60 2760);
WIRE 16 -1 (-275 3050)(1000 3050);
FORCEPROP 2 LAST SIG_NAME A_P5V_SCALED
J 0
(-75 3060);
DISPLAY 0.680851 (-75 3060);
PAINT ORANGE (-75 3060);
WIRE 16 -1 (975 4000)(1725 4000);
FORCEPROP 2 LAST SIG_NAME RMII_BMC_OCP_TXEN
J 2
(1725 4010);
DISPLAY 0.680851 (1725 4010);
PAINT ORANGE (1725 4010);
WIRE 16 -1 (-275 2950)(1000 2950);
FORCEPROP 2 LAST SIG_NAME A_PVNN_STBY_PCH_SENSOR
J 0
(-75 2960);
DISPLAY 0.680851 (-75 2960);
PAINT ORANGE (-75 2960);
WIRE 16 -1 (-275 2900)(1000 2900);
FORCEPROP 2 LAST SIG_NAME A_P3V3_SCALED
J 0
(-75 2910);
DISPLAY 0.680851 (-75 2910);
PAINT ORANGE (-75 2910);
WIRE 16 -1 (-275 2700)(1025 2700);
FORCEPROP 2 LAST SIG_NAME FM_UARTSW_LSB_N
J 0
(-60 2710);
DISPLAY 0.680851 (-60 2710);
PAINT ORANGE (-60 2710);
WIRE 16 -1 (-275 2650)(1025 2650);
FORCEPROP 0 LAST CDS_PHYS_NET_NAME FM_CPLD_BMC_PWRDN_N
J 0
(-260 2689);
PAINT MONO (-260 2689);
DISPLAY INVISIBLE (-260 2689);
FORCEPROP 2 LAST SIG_NAME FM_CPLD_BMC_PWRDN_N
J 0
(-60 2660);
DISPLAY 0.680851 (-60 2660);
PAINT ORANGE (-60 2660);
FORCEPROP 0 LAST PHYS_NET_NAME FM_CPLD_BMC_PWRDN_N
J 0
(-260 2736);
PAINT MONO (-260 2736);
DISPLAY INVISIBLE (-260 2736);
WIRE 16 -1 (-275 2550)(1025 2550);
FORCEPROP 2 LAST SIG_NAME FM_CPU_MSMI_LVT3_N
J 0
(-60 2560);
DISPLAY 0.680851 (-60 2560);
PAINT ORANGE (-60 2560);
WIRE 16 -1 (-275 2450)(1025 2450);
FORCEPROP 2 LAST SIG_NAME FAN_PWM_OUT_SYS1
J 2
(525 2460);
DISPLAY 0.680851 (525 2460);
PAINT ORANGE (525 2460);
WIRE 16 -1 (-275 3000)(1000 3000);
FORCEPROP 2 LAST SIG_NAME A_P1V05_STBY_PCH_SENSOR
J 0
(-75 3010);
DISPLAY 0.680851 (-75 3010);
PAINT ORANGE (-75 3010);
WIRE 16 -1 (-275 2600)(1025 2600);
FORCEPROP 2 LAST SIG_NAME FM_BACKUP_BIOS_SEL_N
J 0
(-60 2610);
DISPLAY 0.680851 (-60 2610);
PAINT ORANGE (-60 2610);
WIRE 16 -1 (-275 2500)(-100 2500);
WIRE 16 -1 (-100 2500)(1025 2500);
FORCEPROP 2 LAST SIG_NAME FM_BIOS_PREFRB2_GOOD
J 0
(65 2510);
DISPLAY 0.680851 (65 2510);
PAINT ORANGE (65 2510);
WIRE 16 -1 (-100 1925)(-100 2500);
WIRE 16 -1 (-4725 3450)(-3375 3450);
FORCEPROP 2 LAST SIG_NAME FM_CPU0_PROC_ID1
J 0
(-4575 3460);
DISPLAY 0.680851 (-4575 3460);
PAINT ORANGE (-4575 3460);
WIRE 16 -1 (975 3750)(1725 3750);
FORCEPROP 2 LAST SIG_NAME RMII_BMC_OCP_TXD0
J 2
(1725 3760);
DISPLAY 0.680851 (1725 3760);
PAINT ORANGE (1725 3760);
WIRE 16 -1 (975 3800)(1725 3800);
FORCEPROP 2 LAST SIG_NAME RMII_BMC_OCP_TXD1
J 2
(1725 3810);
DISPLAY 0.680851 (1725 3810);
PAINT ORANGE (1725 3810);
WIRE 16 -1 (1025 4400)(2250 4400);
FORCEPROP 2 LAST SIG_NAME RMII_BMC_PCH_SPRNGVLLE_TXEN
J 2
(1925 4410);
DISPLAY 0.680851 (1925 4410);
PAINT ORANGE (1925 4410);
WIRE 16 -1 (2250 4200)(2200 4200);
WIRE 16 -1 (2200 4200)(2200 4650);
WIRE 16 -1 (1025 4200)(2200 4200);
FORCEPROP 2 LAST SIG_NAME RMII_BMC_PCH_SPRNGVLLE_TXD1
J 2
(1925 4210);
DISPLAY 0.680851 (1925 4210);
PAINT ORANGE (1925 4210);
WIRE 16 -1 (1950 4675)(1950 4150);
WIRE 16 -1 (1950 4150)(2250 4150);
WIRE 16 -1 (1025 4150)(1950 4150);
FORCEPROP 2 LAST SIG_NAME RMII_BMC_PCH_SPRNGVLLE_TXD0
J 2
(1925 4160);
DISPLAY 0.680851 (1925 4160);
PAINT ORANGE (1925 4160);
WIRE 16 -1 (-275 2400)(1025 2400);
FORCEPROP 2 LAST SIG_NAME FAN_PWM_OUT_SYS0
J 2
(525 2410);
DISPLAY 0.680851 (525 2410);
PAINT ORANGE (525 2410);
WIRE 16 -1 (1625 2225)(1625 2300);
WIRE 16 -1 (1625 2300)(1900 2300);
WIRE 16 -1 (-275 2300)(1625 2300);
FORCEPROP 0 LAST VOLTAGE +3.3V
J 0
(500 2350);
DISPLAY 1.021277 (500 2350);
PAINT SKYBLUE (500 2350);
DISPLAY INVISIBLE (500 2350);
FORCEPROP 0 LAST SIG_NAME P3V3_STBY_BMC_ADCVREFP
J 0
(-42 2311);
DISPLAY 0.680851 (-42 2311);
PAINT ORANGE (-42 2311);
FORCEPROP 2 LASTPROP $XRERR UNIQUE?
J 0
(-282 2311);
DISPLAY 0.638298 (-282 2311);
PAINT MONO (-282 2311);
DISPLAY INVISIBLE (-282 2311);
WIRE 16 -1 (775 2025)(775 2150);
WIRE 16 -1 (775 2150)(-275 2150);
FORCEPROP 0 LAST CDS_PHYS_NET_NAME PD_ADCREXT
J 0
(-60 2189);
PAINT MONO (-60 2189);
DISPLAY INVISIBLE (-60 2189);
FORCEPROP 2 LAST SIG_NAME PD_ADCREXT
J 0
(-60 2160);
DISPLAY 0.680851 (-60 2160);
PAINT ORANGE (-60 2160);
FORCEPROP 2 LASTPROP $XRERR UNIQUE?
J 0
(-300 2160);
DISPLAY 0.638298 (-300 2160);
PAINT MONO (-300 2160);
DISPLAY INVISIBLE (-300 2160);
WIRE 16 -1 (1625 2025)(1625 1950);
WIRE 16 -1 (1625 1950)(1900 1950);
WIRE 16 -1 (1275 1950)(1625 1950);
WIRE 16 -1 (1275 2250)(1275 1950);
WIRE 16 -1 (-275 2250)(1275 2250);
FORCEPROP 0 LAST VOLTAGE +3.3V
J 0
(75 2325);
DISPLAY 1.021277 (75 2325);
PAINT SKYBLUE (75 2325);
DISPLAY INVISIBLE (75 2325);
FORCEPROP 0 LAST SIG_NAME P3V3_STBY_BMC_ADCVREFN
J 0
(-42 2261);
DISPLAY 0.680851 (-42 2261);
PAINT ORANGE (-42 2261);
FORCEPROP 2 LASTPROP $XRERR UNIQUE?
J 0
(-282 2261);
DISPLAY 0.638298 (-282 2261);
PAINT MONO (-282 2261);
DISPLAY INVISIBLE (-282 2261);
DOT 1 (-3525 4400);
DOT 1 (-3900 5000);
DOT 1 (-3650 4150);
DOT 1 (-3900 4200);
DOT 1 (675 4200);
DOT 1 (2200 4200);
DOT 1 (1950 4150);
DOT 1 (1950 4975);
DOT 1 (625 4150);
DOT 1 (550 3750);
DOT 1 (1625 2300);
DOT 1 (1625 1950);
DOT 1 (500 3800);
DOT 1 (-100 2500);
DOT 1 (-3525 2500);
DOT 1 (-3775 2450);
DOT 1 (-4025 2400);
DOT 1 (-4275 2350);
FORCENOTE
ROOM=SM_CONTROLLER
(-5083 798) 0;
DISPLAY LEFT (-5083 798);
DISPLAY 0.617021 (-5083 798);
PAINT PURPLE (-5083 798);
QUIT
